# Altium SchDoc records: USER_IO.SchDoc
|HEADER=Protel for Windows - Schematic Capture Binary File Version 5.0|Weight=1570|MinorVersion=2
|RECORD=31|FontIdCount=8|Size1=10|FontName1=Times New Roman|Size2=10|Underline2=T|FontName2=Times New Roman|Size3=12|FontName3=Arial|Size4=14|FontName4=Arial|Size5=8|FontName5=Arial|Size6=24|FontName6=Times New Roman|Size7=10|FontName7=Arial|Size8=12|Underline8=T|FontName8=Arial|UseMBCS=T|IsBOC=T|HotSpotGridOn=T|HotSpotGridSize=4|SheetStyle=12|SystemFont=7|BorderOn=T|SheetNumberSpaceSize=12|AreaColor=16317695|SnapGridOn=T|SnapGridSize=10|VisibleGridOn=T|VisibleGridSize=10|CustomX=2338|CustomX_Frac=58268|CustomY=1653|CustomY_Frac=54331|CustomXZones=8|CustomYZones=6|CustomMarginWidth=19|CustomMarginWidth_Frac=80000|ShowTemplateGraphics=T|TemplateFileName=C:\Users\<user>\Documents\Altium\AD20\Templates\Timecard.SchDot|Display_Unit=0
|RECORD=39|IsNotAccesible=T|OwnerPartId=-1|FileName=C:\Users\<user>\Documents\Altium\AD20\Templates\Timecard.SchDot
|RECORD=4|OwnerIndex=1|OwnerPartId=-1|Location.X=1594|Location.Y=39|Color=8388608|FontID=8|Text=timingcard.com|URL=http://timingcard.com
|RECORD=6|OwnerIndex=1|IndexInSheet=1|OwnerPartId=-1|LocationCount=2|X1=1680|Y1=35|X2=1576|Y2=35
|RECORD=4|OwnerIndex=1|IndexInSheet=2|OwnerPartId=-1|Location.X=1614|Location.X_Frac=42446|Location.Y=19|Location.Y_Frac=96838|FontID=3|Text==SheetNumber
|RECORD=4|OwnerIndex=1|IndexInSheet=3|OwnerPartId=-1|Location.X=1581|Location.X_Frac=42446|Location.Y=29|Location.Y_Frac=96838|Justification=3|FontID=5|Text=SHEET
|RECORD=4|OwnerIndex=1|IndexInSheet=4|OwnerPartId=-1|Location.X=1639|Location.X_Frac=42446|Location.Y=29|Location.Y_Frac=96838|Justification=3|FontID=5|Text=OF
|RECORD=6|OwnerIndex=1|IndexInSheet=5|OwnerPartId=-1|LineWidth=1|LocationCount=2|X1=1679|X1_Frac=42446|Y1=105|Y1_Frac=96838|X2=1576|Y2=106
|RECORD=4|OwnerIndex=1|IndexInSheet=6|OwnerPartId=-1|Location.X=1658|Location.Y=20|FontID=3|Text==SheetTotal
|RECORD=30|OwnerIndex=1|IndexInSheet=7|OwnerPartId=-1|Location.X=1578|Location.Y=53|Corner.X=1673|Corner.X_Frac=88801|Corner.Y=103|KeepAspect=T|FileName=C:\Users\<user>\Desktop\Timecard Logo\TIMECARD.jpg
|RECORD=6|OwnerIndex=1|IndexInSheet=8|OwnerPartId=-1|LineWidth=1|LocationCount=2|X1=1576|X1_Frac=3162|Y1=105|Y1_Frac=42446|X2=1576|Y2=20
|RECORD=6|OwnerIndex=1|IndexInSheet=9|OwnerPartId=-1|LocationCount=2|X1=1680|Y1=51|X2=1576|Y2=51
|RECORD=41|IndexInSheet=1|OwnerPartId=-1|Color=8388608|FontID=1|IsHidden=T|Text=*|Name=CurrentTime|ReadOnlyState=1
|RECORD=41|IndexInSheet=2|OwnerPartId=-1|Color=8388608|FontID=1|IsHidden=T|Text=*|Name=CurrentDate|ReadOnlyState=1
|RECORD=41|IndexInSheet=3|OwnerPartId=-1|Color=8388608|FontID=1|IsHidden=T|Text=*|Name=Time|ReadOnlyState=1
|RECORD=41|IndexInSheet=4|OwnerPartId=-1|Color=8388608|FontID=1|IsHidden=T|Text=*|Name=Date|ReadOnlyState=1
|RECORD=41|IndexInSheet=5|OwnerPartId=-1|Color=8388608|FontID=1|IsHidden=T|Text=*|Name=DocumentFullPathAndName|ReadOnlyState=1
|RECORD=41|IndexInSheet=6|OwnerPartId=-1|Color=8388608|FontID=1|IsHidden=T|Text=*|Name=DocumentName|ReadOnlyState=1
|RECORD=41|IndexInSheet=7|OwnerPartId=-1|Color=8388608|FontID=1|IsHidden=T|Text=*|Name=ModifiedDate|ReadOnlyState=1
|RECORD=41|IndexInSheet=8|OwnerPartId=-1|Color=8388608|FontID=1|IsHidden=T|Text=*|Name=ApprovedBy|ReadOnlyState=1
|RECORD=41|IndexInSheet=9|OwnerPartId=-1|Color=8388608|FontID=1|IsHidden=T|Text=*|Name=CheckedBy|ReadOnlyState=1
|RECORD=41|IndexInSheet=10|OwnerPartId=-1|Color=8388608|FontID=1|IsHidden=T|Text=*|Name=Author|ReadOnlyState=1
|RECORD=41|IndexInSheet=11|OwnerPartId=-1|Color=8388608|FontID=1|IsHidden=T|Text=*|Name=CompanyName|ReadOnlyState=1
|RECORD=41|IndexInSheet=12|OwnerPartId=-1|Color=8388608|FontID=1|IsHidden=T|Text=*|Name=DrawnBy|ReadOnlyState=1
|RECORD=41|IndexInSheet=13|OwnerPartId=-1|Color=8388608|FontID=1|IsHidden=T|Text=*|Name=Engineer|ReadOnlyState=1
|RECORD=41|IndexInSheet=14|OwnerPartId=-1|Color=8388608|FontID=1|IsHidden=T|Text=*|Name=Organization|ReadOnlyState=1
|RECORD=41|IndexInSheet=15|OwnerPartId=-1|Color=8388608|FontID=1|IsHidden=T|Text=*|Name=Address1|ReadOnlyState=1
|RECORD=41|IndexInSheet=16|OwnerPartId=-1|Color=8388608|FontID=1|IsHidden=T|Text=*|Name=Address2|ReadOnlyState=1
|RECORD=41|IndexInSheet=17|OwnerPartId=-1|Color=8388608|FontID=1|IsHidden=T|Text=*|Name=Address3|ReadOnlyState=1
|RECORD=41|IndexInSheet=18|OwnerPartId=-1|Color=8388608|FontID=1|IsHidden=T|Text=*|Name=Address4|ReadOnlyState=1
|RECORD=41|IndexInSheet=19|OwnerPartId=-1|Color=8388608|FontID=1|IsHidden=T|Text=*|Name=Title|ReadOnlyState=1
|RECORD=41|IndexInSheet=20|OwnerPartId=-1|Color=8388608|FontID=1|IsHidden=T|Text=*|Name=DocumentNumber|ReadOnlyState=1
|RECORD=41|IndexInSheet=21|OwnerPartId=-1|Color=8388608|FontID=1|IsHidden=T|Text=*|Name=Revision|ReadOnlyState=1
|RECORD=41|IndexInSheet=22|OwnerPartId=-1|Color=8388608|FontID=1|IsHidden=T|Text=1|Name=SheetNumber|ReadOnlyState=1
|RECORD=41|IndexInSheet=23|OwnerPartId=-1|Color=8388608|FontID=1|IsHidden=T|Text=7|Name=SheetTotal|ReadOnlyState=1
|RECORD=41|IndexInSheet=24|OwnerPartId=-1|Color=8388608|FontID=1|IsHidden=T|Text=*|Name=Rule|ReadOnlyState=1
|RECORD=41|IndexInSheet=25|OwnerPartId=-1|Color=8388608|FontID=1|IsHidden=T|Text=*|Name=ImagePath|ReadOnlyState=1
|RECORD=41|IndexInSheet=26|OwnerPartId=-1|Color=8388608|FontID=1|IsHidden=T|Text=*|Name=ProjectName|ReadOnlyState=1
|RECORD=41|IndexInSheet=27|OwnerPartId=-1|Color=8388608|FontID=1|IsHidden=T|Text=*|Name=Application_BuildNumber|ReadOnlyState=1
|RECORD=17|IndexInSheet=28|OwnerPartId=-1|ShowNetName=T|Location.X=1050|Location.Y=950|Orientation=1|Color=128|FontID=1|Text=+3.3V
|RECORD=17|IndexInSheet=29|OwnerPartId=-1|ShowNetName=T|Location.X=950|Location.Y=950|Orientation=1|Color=128|FontID=1|Text=+3.3V
|RECORD=17|IndexInSheet=30|OwnerPartId=-1|ShowNetName=T|Location.X=850|Location.Y=950|Orientation=1|Color=128|FontID=1|Text=+3.3V
|RECORD=17|IndexInSheet=31|OwnerPartId=-1|ShowNetName=T|Location.X=750|Location.Y=950|Orientation=1|Color=128|FontID=1|Text=+3.3V
|RECORD=17|IndexInSheet=32|OwnerPartId=-1|ShowNetName=T|Location.X=740|Location.Y=820|Orientation=2|Color=255|FontID=1|Text=LED1|IsCrossSheetConnector=T
|RECORD=17|IndexInSheet=33|OwnerPartId=-1|ShowNetName=T|Location.X=840|Location.Y=820|Orientation=2|Color=255|FontID=1|Text=LED2|IsCrossSheetConnector=T
|RECORD=17|IndexInSheet=34|OwnerPartId=-1|ShowNetName=T|Location.X=940|Location.Y=820|Orientation=2|Color=255|FontID=1|Text=LED3|IsCrossSheetConnector=T
|RECORD=17|IndexInSheet=35|OwnerPartId=-1|ShowNetName=T|Location.X=1040|Location.Y=820|Orientation=2|Color=255|FontID=1|Text=LED4|IsCrossSheetConnector=T
|RECORD=1|LibReference=SMTLED_RED_0603_SML|ComponentDescription=LED, RED, SML-LX0603, 635NM, 2V, 20MA, 0603|PartCount=2|DisplayModeCount=1|IndexInSheet=36|OwnerPartId=-1|Location.X=1050|Location.Y=950|Orientation=3|CurrentPartId=1|LibraryPath=*|SourceLibraryName=Passives.IntLib|TargetFileName=*|AreaColor=11599871|Color=128|PartIDLocked=F|DesignItemId=SMTLED_RED_0603_SML|AllPinCount=2
|RECORD=41|OwnerIndex=47|OwnerPartId=-1|Location.X=1037|Location.X_Frac=50000|Location.Y=952|Color=8388608|FontID=3|IsHidden=T|Text=SML-LX0603IW-TR|Name=MFG PART NUM
|RECORD=41|OwnerIndex=47|IndexInSheet=1|OwnerPartId=-1|Location.X=1037|Location.X_Frac=50000|Location.Y=952|Color=8388608|FontID=3|IsHidden=T|Text=9/4/2013|Name=MODIFY DATE
|RECORD=41|OwnerIndex=47|IndexInSheet=2|OwnerPartId=-1|Location.X=1037|Location.X_Frac=50000|Location.Y=952|Color=8388608|FontID=3|IsHidden=T|Text=LUMEX|Name=MFG NAME
|RECORD=41|OwnerIndex=47|IndexInSheet=3|OwnerPartId=-1|Location.X=1037|Location.X_Frac=50000|Location.Y=952|Color=8388608|FontID=3|IsHidden=T|Text=LED|Name=CATEGORY
|RECORD=41|OwnerIndex=47|IndexInSheet=4|OwnerPartId=-1|Location.X=1037|Location.X_Frac=50000|Location.Y=952|Color=8388608|FontID=3|IsHidden=T|Name=Date
|RECORD=41|OwnerIndex=47|IndexInSheet=5|OwnerPartId=-1|Location.X=1037|Location.X_Frac=50000|Location.Y=952|Color=8388608|FontID=3|IsHidden=T|Text=85C|Name=MAXTEMP
|RECORD=41|OwnerIndex=47|IndexInSheet=6|OwnerPartId=-1|Location.X=1037|Location.X_Frac=50000|Location.Y=952|Color=8388608|FontID=3|IsHidden=T|Text=-25C|Name=MINTEMP
|RECORD=41|OwnerIndex=47|IndexInSheet=7|OwnerPartId=-1|Location.X=1037|Location.X_Frac=50000|Location.Y=952|Color=8388608|FontID=3|IsHidden=T|Text=SML-LX0603|Name=OTHER
|RECORD=41|OwnerIndex=47|IndexInSheet=8|OwnerPartId=-1|Location.X=1037|Location.X_Frac=50000|Location.Y=952|Color=8388608|FontID=3|IsHidden=T|Text=635NM|Name=P1
|RECORD=41|OwnerIndex=47|IndexInSheet=9|OwnerPartId=-1|Location.X=1037|Location.X_Frac=50000|Location.Y=952|Color=8388608|FontID=3|IsHidden=T|Text=2V|Name=P2
|RECORD=41|OwnerIndex=47|IndexInSheet=10|OwnerPartId=-1|Location.X=1037|Location.X_Frac=50000|Location.Y=952|Color=8388608|FontID=3|IsHidden=T|Text=20MA|Name=P3
|RECORD=41|OwnerIndex=47|IndexInSheet=11|OwnerPartId=-1|Location.X=1037|Location.X_Frac=50000|Location.Y=952|Color=8388608|FontID=3|IsHidden=T|Name=SUB
|RECORD=41|OwnerIndex=47|IndexInSheet=12|OwnerPartId=-1|Location.X=1037|Location.X_Frac=50000|Location.Y=952|Color=8388608|FontID=3|IsHidden=T|Text=0603|Name=SIZE
|RECORD=41|OwnerIndex=47|IndexInSheet=13|OwnerPartId=-1|Location.X=1037|Location.X_Frac=50000|Location.Y=952|Color=8388608|FontID=1|IsHidden=T|Text=*|Name=SHEETPART
|RECORD=41|OwnerIndex=47|IndexInSheet=14|OwnerPartId=-1|Location.X=1037|Location.X_Frac=50000|Location.Y=952|Color=8388608|FontID=1|IsHidden=T|Text=LED, RED, SML-LX0603, 635NM, 2V, 20MA, 0603|Name=DESC
|RECORD=41|OwnerIndex=47|IndexInSheet=15|OwnerPartId=-1|Location.X=1037|Location.X_Frac=50000|Location.Y=952|Color=8388608|FontID=1|IsHidden=T|Text=Digi-Key|Name=Supplier 1|ReadOnlyState=3
|RECORD=41|OwnerIndex=47|IndexInSheet=16|OwnerPartId=-1|Location.X=1037|Location.X_Frac=50000|Location.Y=952|Color=8388608|FontID=1|IsHidden=T|Text=67-1548-1-ND|Name=Supplier Part Number 1|ReadOnlyState=3
|RECORD=41|OwnerIndex=47|IndexInSheet=17|OwnerPartId=-1|Location.X=1070|Location.Y=906|Location.Y_Frac=50000|Color=8388608|FontID=3|Text=RED|Name=VALUE
|RECORD=2|OwnerIndex=47|OwnerPartId=1|FormalType=1|Electrical=4|PinConglomerate=33|PinLength=20|Location.X=1050|Location.Y=930|Name=A|Designator=2|PinPropagationDelay=0.000000E+000
|RECORD=2|OwnerIndex=47|OwnerPartId=1|FormalType=1|Electrical=4|PinConglomerate=35|PinLength=20|Location.X=1050|Location.Y=910|Name=K|Designator=1|PinPropagationDelay=0.000000E+000
|RECORD=12|OwnerIndex=47|IsNotAccesible=T|IndexInSheet=20|OwnerPartId=1|Location.X=1050|Location.Y=920|Radius=12|Radius_Frac=50000|LineWidth=1|EndAngle=360.000|Color=16711680
|RECORD=13|OwnerIndex=47|IsNotAccesible=T|IndexInSheet=21|OwnerPartId=1|Location.X=1058|Location.Y=914|Corner.X=1043|Corner.Y=914|LineWidth=1|Color=16711680
|RECORD=13|OwnerIndex=47|IsNotAccesible=T|IndexInSheet=22|OwnerPartId=1|Location.X=1065|Location.Y=901|Corner.X=1058|Corner.X_Frac=70000|Corner.Y=907|Corner.Y_Frac=20000|LineWidth=1|Color=16711680
|RECORD=13|OwnerIndex=47|IsNotAccesible=T|IndexInSheet=23|OwnerPartId=1|Location.X=1069|Location.Y=905|Corner.X=1062|Corner.X_Frac=80000|Corner.Y=911|Corner.Y_Frac=30000|LineWidth=1|Color=16711680
|RECORD=13|OwnerIndex=47|IsNotAccesible=T|IndexInSheet=24|OwnerPartId=1|Location.X=1050|Location.Y=910|Corner.X=1050|Corner.Y=913|Corner.Y_Frac=80000|LineWidth=1|Color=16711680
|RECORD=13|OwnerIndex=47|IsNotAccesible=T|IndexInSheet=25|OwnerPartId=1|Location.X=1050|Location.Y=926|Corner.X=1050|Corner.Y=929|Corner.Y_Frac=70000|LineWidth=1|Color=16711680
|RECORD=7|OwnerIndex=47|IsNotAccesible=T|IndexInSheet=26|OwnerPartId=1|LineWidth=1|Color=16711680|AreaColor=16711680|IsSolid=T|LocationCount=3|X1=1064|Y1=904|X2=1062|Y2=902|X3=1065|Y3=901
|RECORD=7|OwnerIndex=47|IsNotAccesible=T|IndexInSheet=27|OwnerPartId=1|LineWidth=1|Color=16711680|AreaColor=16711680|IsSolid=T|LocationCount=3|X1=1068|Y1=908|X2=1066|Y2=906|X3=1069|Y3=905
|RECORD=7|OwnerIndex=47|IsNotAccesible=T|IndexInSheet=28|OwnerPartId=1|LineWidth=1|Color=16711680|AreaColor=16777215|IsSolid=T|LocationCount=3|X1=1050|Y1=914|X2=1058|Y2=926|X3=1042|Y3=926
|RECORD=41|OwnerIndex=47|IndexInSheet=29|OwnerPartId=-1|Location.X=1037|Location.X_Frac=50000|Location.Y=952|Color=8388608|FontID=1|IsHidden=T|Text=<VALENTIUM>|Name=VALENTIUM PART NUM
|RECORD=34|OwnerIndex=47|IndexInSheet=-1|OwnerPartId=-1|Location.X=1070|Location.Y=918|Location.Y_Frac=50000|Color=8388608|FontID=4|Text=D14|Name=Designator|ReadOnlyState=1
|RECORD=41|OwnerIndex=47|IndexInSheet=-1|OwnerPartId=-1|Location.X=1037|Location.X_Frac=50000|Location.Y=952|Color=8388608|FontID=3|IsHidden=T|Text==VALUE|Name=Comment|ReadOnlyState=1
|RECORD=44|OwnerIndex=47
|RECORD=45|OwnerIndex=82|IndexInSheet=-1|Description=Molded Diode, 0603, 2-Leads, Body 1.60x0.80mm, IPC Medium Density|UseComponentLibrary=T|ModelName=DIOM1608X06N|ModelType=PCBLIB|DatafileCount=1|ModelDatafileEntity0=DIOM1608X06N|ModelDatafileKind0=PCBLib|IsCurrent=T|DatalinksLocked=T|DatabaseDatalinksLocked=T|IntegratedModel=T|DatabaseModel=T
|RECORD=46|OwnerIndex=83
|RECORD=48|OwnerIndex=83
|RECORD=1|LibReference=SMTLED_RED_0603_SML|ComponentDescription=LED, RED, SML-LX0603, 635NM, 2V, 20MA, 0603|PartCount=2|DisplayModeCount=1|IndexInSheet=37|OwnerPartId=-1|Location.X=950|Location.Y=950|Orientation=3|CurrentPartId=1|LibraryPath=*|SourceLibraryName=Passives.IntLib|TargetFileName=*|AreaColor=11599871|Color=128|PartIDLocked=F|DesignItemId=SMTLED_RED_0603_SML|AllPinCount=2
|RECORD=41|OwnerIndex=86|OwnerPartId=-1|Location.X=937|Location.X_Frac=50000|Location.Y=952|Color=8388608|FontID=3|IsHidden=T|Text=SML-LX0603IW-TR|Name=MFG PART NUM
|RECORD=41|OwnerIndex=86|IndexInSheet=1|OwnerPartId=-1|Location.X=937|Location.X_Frac=50000|Location.Y=952|Color=8388608|FontID=3|IsHidden=T|Text=9/4/2013|Name=MODIFY DATE
|RECORD=41|OwnerIndex=86|IndexInSheet=2|OwnerPartId=-1|Location.X=937|Location.X_Frac=50000|Location.Y=952|Color=8388608|FontID=3|IsHidden=T|Text=LUMEX|Name=MFG NAME
|RECORD=41|OwnerIndex=86|IndexInSheet=3|OwnerPartId=-1|Location.X=937|Location.X_Frac=50000|Location.Y=952|Color=8388608|FontID=3|IsHidden=T|Text=LED|Name=CATEGORY
|RECORD=41|OwnerIndex=86|IndexInSheet=4|OwnerPartId=-1|Location.X=937|Location.X_Frac=50000|Location.Y=952|Color=8388608|FontID=3|IsHidden=T|Name=Date
|RECORD=41|OwnerIndex=86|IndexInSheet=5|OwnerPartId=-1|Location.X=937|Location.X_Frac=50000|Location.Y=952|Color=8388608|FontID=3|IsHidden=T|Text=85C|Name=MAXTEMP
|RECORD=41|OwnerIndex=86|IndexInSheet=6|OwnerPartId=-1|Location.X=937|Location.X_Frac=50000|Location.Y=952|Color=8388608|FontID=3|IsHidden=T|Text=-25C|Name=MINTEMP
|RECORD=41|OwnerIndex=86|IndexInSheet=7|OwnerPartId=-1|Location.X=937|Location.X_Frac=50000|Location.Y=952|Color=8388608|FontID=3|IsHidden=T|Text=SML-LX0603|Name=OTHER
|RECORD=41|OwnerIndex=86|IndexInSheet=8|OwnerPartId=-1|Location.X=937|Location.X_Frac=50000|Location.Y=952|Color=8388608|FontID=3|IsHidden=T|Text=635NM|Name=P1
|RECORD=41|OwnerIndex=86|IndexInSheet=9|OwnerPartId=-1|Location.X=937|Location.X_Frac=50000|Location.Y=952|Color=8388608|FontID=3|IsHidden=T|Text=2V|Name=P2
|RECORD=41|OwnerIndex=86|IndexInSheet=10|OwnerPartId=-1|Location.X=937|Location.X_Frac=50000|Location.Y=952|Color=8388608|FontID=3|IsHidden=T|Text=20MA|Name=P3
|RECORD=41|OwnerIndex=86|IndexInSheet=11|OwnerPartId=-1|Location.X=937|Location.X_Frac=50000|Location.Y=952|Color=8388608|FontID=3|IsHidden=T|Name=SUB
|RECORD=41|OwnerIndex=86|IndexInSheet=12|OwnerPartId=-1|Location.X=937|Location.X_Frac=50000|Location.Y=952|Color=8388608|FontID=3|IsHidden=T|Text=0603|Name=SIZE
|RECORD=41|OwnerIndex=86|IndexInSheet=13|OwnerPartId=-1|Location.X=937|Location.X_Frac=50000|Location.Y=952|Color=8388608|FontID=1|IsHidden=T|Text=*|Name=SHEETPART
|RECORD=41|OwnerIndex=86|IndexInSheet=14|OwnerPartId=-1|Location.X=937|Location.X_Frac=50000|Location.Y=952|Color=8388608|FontID=1|IsHidden=T|Text=LED, RED, SML-LX0603, 635NM, 2V, 20MA, 0603|Name=DESC
|RECORD=41|OwnerIndex=86|IndexInSheet=15|OwnerPartId=-1|Location.X=937|Location.X_Frac=50000|Location.Y=952|Color=8388608|FontID=1|IsHidden=T|Text=Digi-Key|Name=Supplier 1|ReadOnlyState=3
|RECORD=41|OwnerIndex=86|IndexInSheet=16|OwnerPartId=-1|Location.X=937|Location.X_Frac=50000|Location.Y=952|Color=8388608|FontID=1|IsHidden=T|Text=67-1548-1-ND|Name=Supplier Part Number 1|ReadOnlyState=3
|RECORD=41|OwnerIndex=86|IndexInSheet=17|OwnerPartId=-1|Location.X=970|Location.Y=906|Location.Y_Frac=50000|Color=8388608|FontID=3|Text=RED|Name=VALUE
|RECORD=2|OwnerIndex=86|OwnerPartId=1|FormalType=1|Electrical=4|PinConglomerate=33|PinLength=20|Location.X=950|Location.Y=930|Name=A|Designator=2|PinPropagationDelay=0.000000E+000
|RECORD=2|OwnerIndex=86|OwnerPartId=1|FormalType=1|Electrical=4|PinConglomerate=35|PinLength=20|Location.X=950|Location.Y=910|Name=K|Designator=1|PinPropagationDelay=0.000000E+000
|RECORD=12|OwnerIndex=86|IsNotAccesible=T|IndexInSheet=20|OwnerPartId=1|Location.X=950|Location.Y=920|Radius=12|Radius_Frac=50000|LineWidth=1|EndAngle=360.000|Color=16711680
|RECORD=13|OwnerIndex=86|IsNotAccesible=T|IndexInSheet=21|OwnerPartId=1|Location.X=958|Location.Y=914|Corner.X=943|Corner.Y=914|LineWidth=1|Color=16711680
|RECORD=13|OwnerIndex=86|IsNotAccesible=T|IndexInSheet=22|OwnerPartId=1|Location.X=965|Location.Y=901|Corner.X=958|Corner.X_Frac=70000|Corner.Y=907|Corner.Y_Frac=20000|LineWidth=1|Color=16711680
|RECORD=13|OwnerIndex=86|IsNotAccesible=T|IndexInSheet=23|OwnerPartId=1|Location.X=969|Location.Y=905|Corner.X=962|Corner.X_Frac=80000|Corner.Y=911|Corner.Y_Frac=30000|LineWidth=1|Color=16711680
|RECORD=13|OwnerIndex=86|IsNotAccesible=T|IndexInSheet=24|OwnerPartId=1|Location.X=950|Location.Y=910|Corner.X=950|Corner.Y=913|Corner.Y_Frac=80000|LineWidth=1|Color=16711680
|RECORD=13|OwnerIndex=86|IsNotAccesible=T|IndexInSheet=25|OwnerPartId=1|Location.X=950|Location.Y=926|Corner.X=950|Corner.Y=929|Corner.Y_Frac=70000|LineWidth=1|Color=16711680
|RECORD=7|OwnerIndex=86|IsNotAccesible=T|IndexInSheet=26|OwnerPartId=1|LineWidth=1|Color=16711680|AreaColor=16711680|IsSolid=T|LocationCount=3|X1=964|Y1=904|X2=962|Y2=902|X3=965|Y3=901
|RECORD=7|OwnerIndex=86|IsNotAccesible=T|IndexInSheet=27|OwnerPartId=1|LineWidth=1|Color=16711680|AreaColor=16711680|IsSolid=T|LocationCount=3|X1=968|Y1=908|X2=966|Y2=906|X3=969|Y3=905
|RECORD=7|OwnerIndex=86|IsNotAccesible=T|IndexInSheet=28|OwnerPartId=1|LineWidth=1|Color=16711680|AreaColor=16777215|IsSolid=T|LocationCount=3|X1=950|Y1=914|X2=958|Y2=926|X3=942|Y3=926
|RECORD=41|OwnerIndex=86|IndexInSheet=29|OwnerPartId=-1|Location.X=937|Location.X_Frac=50000|Location.Y=952|Color=8388608|FontID=1|IsHidden=T|Text=<VALENTIUM>|Name=VALENTIUM PART NUM
|RECORD=34|OwnerIndex=86|IndexInSheet=-1|OwnerPartId=-1|Location.X=970|Location.Y=918|Location.Y_Frac=50000|Color=8388608|FontID=4|Text=D13|Name=Designator|ReadOnlyState=1
|RECORD=41|OwnerIndex=86|IndexInSheet=-1|OwnerPartId=-1|Location.X=937|Location.X_Frac=50000|Location.Y=952|Color=8388608|FontID=3|IsHidden=T|Text==VALUE|Name=Comment|ReadOnlyState=1
|RECORD=44|OwnerIndex=86
|RECORD=45|OwnerIndex=121|IndexInSheet=-1|Description=Molded Diode, 0603, 2-Leads, Body 1.60x0.80mm, IPC Medium Density|UseComponentLibrary=T|ModelName=DIOM1608X06N|ModelType=PCBLIB|DatafileCount=1|ModelDatafileEntity0=DIOM1608X06N|ModelDatafileKind0=PCBLib|IsCurrent=T|DatalinksLocked=T|DatabaseDatalinksLocked=T|IntegratedModel=T|DatabaseModel=T
|RECORD=46|OwnerIndex=122
|RECORD=48|OwnerIndex=122
|RECORD=1|LibReference=SMTLED_RED_0603_SML|ComponentDescription=LED, RED, SML-LX0603, 635NM, 2V, 20MA, 0603|PartCount=2|DisplayModeCount=1|IndexInSheet=38|OwnerPartId=-1|Location.X=850|Location.Y=950|Orientation=3|CurrentPartId=1|LibraryPath=*|SourceLibraryName=Passives.IntLib|TargetFileName=*|AreaColor=11599871|Color=128|PartIDLocked=F|DesignItemId=SMTLED_RED_0603_SML|AllPinCount=2
|RECORD=41|OwnerIndex=125|OwnerPartId=-1|Location.X=837|Location.X_Frac=50000|Location.Y=952|Color=8388608|FontID=3|IsHidden=T|Text=SML-LX0603IW-TR|Name=MFG PART NUM
|RECORD=41|OwnerIndex=125|IndexInSheet=1|OwnerPartId=-1|Location.X=837|Location.X_Frac=50000|Location.Y=952|Color=8388608|FontID=3|IsHidden=T|Text=9/4/2013|Name=MODIFY DATE
|RECORD=41|OwnerIndex=125|IndexInSheet=2|OwnerPartId=-1|Location.X=837|Location.X_Frac=50000|Location.Y=952|Color=8388608|FontID=3|IsHidden=T|Text=LUMEX|Name=MFG NAME
|RECORD=41|OwnerIndex=125|IndexInSheet=3|OwnerPartId=-1|Location.X=837|Location.X_Frac=50000|Location.Y=952|Color=8388608|FontID=3|IsHidden=T|Text=LED|Name=CATEGORY
|RECORD=41|OwnerIndex=125|IndexInSheet=4|OwnerPartId=-1|Location.X=837|Location.X_Frac=50000|Location.Y=952|Color=8388608|FontID=3|IsHidden=T|Name=Date
|RECORD=41|OwnerIndex=125|IndexInSheet=5|OwnerPartId=-1|Location.X=837|Location.X_Frac=50000|Location.Y=952|Color=8388608|FontID=3|IsHidden=T|Text=85C|Name=MAXTEMP
|RECORD=41|OwnerIndex=125|IndexInSheet=6|OwnerPartId=-1|Location.X=837|Location.X_Frac=50000|Location.Y=952|Color=8388608|FontID=3|IsHidden=T|Text=-25C|Name=MINTEMP
|RECORD=41|OwnerIndex=125|IndexInSheet=7|OwnerPartId=-1|Location.X=837|Location.X_Frac=50000|Location.Y=952|Color=8388608|FontID=3|IsHidden=T|Text=SML-LX0603|Name=OTHER
|RECORD=41|OwnerIndex=125|IndexInSheet=8|OwnerPartId=-1|Location.X=837|Location.X_Frac=50000|Location.Y=952|Color=8388608|FontID=3|IsHidden=T|Text=635NM|Name=P1
|RECORD=41|OwnerIndex=125|IndexInSheet=9|OwnerPartId=-1|Location.X=837|Location.X_Frac=50000|Location.Y=952|Color=8388608|FontID=3|IsHidden=T|Text=2V|Name=P2
|RECORD=41|OwnerIndex=125|IndexInSheet=10|OwnerPartId=-1|Location.X=837|Location.X_Frac=50000|Location.Y=952|Color=8388608|FontID=3|IsHidden=T|Text=20MA|Name=P3
|RECORD=41|OwnerIndex=125|IndexInSheet=11|OwnerPartId=-1|Location.X=837|Location.X_Frac=50000|Location.Y=952|Color=8388608|FontID=3|IsHidden=T|Name=SUB
|RECORD=41|OwnerIndex=125|IndexInSheet=12|OwnerPartId=-1|Location.X=837|Location.X_Frac=50000|Location.Y=952|Color=8388608|FontID=3|IsHidden=T|Text=0603|Name=SIZE
|RECORD=41|OwnerIndex=125|IndexInSheet=13|OwnerPartId=-1|Location.X=837|Location.X_Frac=50000|Location.Y=952|Color=8388608|FontID=1|IsHidden=T|Text=*|Name=SHEETPART
|RECORD=41|OwnerIndex=125|IndexInSheet=14|OwnerPartId=-1|Location.X=837|Location.X_Frac=50000|Location.Y=952|Color=8388608|FontID=1|IsHidden=T|Text=LED, RED, SML-LX0603, 635NM, 2V, 20MA, 0603|Name=DESC
|RECORD=41|OwnerIndex=125|IndexInSheet=15|OwnerPartId=-1|Location.X=837|Location.X_Frac=50000|Location.Y=952|Color=8388608|FontID=1|IsHidden=T|Text=Digi-Key|Name=Supplier 1|ReadOnlyState=3
|RECORD=41|OwnerIndex=125|IndexInSheet=16|OwnerPartId=-1|Location.X=837|Location.X_Frac=50000|Location.Y=952|Color=8388608|FontID=1|IsHidden=T|Text=67-1548-1-ND|Name=Supplier Part Number 1|ReadOnlyState=3
|RECORD=41|OwnerIndex=125|IndexInSheet=17|OwnerPartId=-1|Location.X=870|Location.Y=906|Location.Y_Frac=50000|Color=8388608|FontID=3|Text=RED|Name=VALUE
|RECORD=2|OwnerIndex=125|OwnerPartId=1|FormalType=1|Electrical=4|PinConglomerate=33|PinLength=20|Location.X=850|Location.Y=930|Name=A|Designator=2|PinPropagationDelay=0.000000E+000
|RECORD=2|OwnerIndex=125|OwnerPartId=1|FormalType=1|Electrical=4|PinConglomerate=35|PinLength=20|Location.X=850|Location.Y=910|Name=K|Designator=1|PinPropagationDelay=0.000000E+000
|RECORD=12|OwnerIndex=125|IsNotAccesible=T|IndexInSheet=20|OwnerPartId=1|Location.X=850|Location.Y=920|Radius=12|Radius_Frac=50000|LineWidth=1|EndAngle=360.000|Color=16711680
|RECORD=13|OwnerIndex=125|IsNotAccesible=T|IndexInSheet=21|OwnerPartId=1|Location.X=858|Location.Y=914|Corner.X=843|Corner.Y=914|LineWidth=1|Color=16711680
|RECORD=13|OwnerIndex=125|IsNotAccesible=T|IndexInSheet=22|OwnerPartId=1|Location.X=865|Location.Y=901|Corner.X=858|Corner.X_Frac=70000|Corner.Y=907|Corner.Y_Frac=20000|LineWidth=1|Color=16711680
|RECORD=13|OwnerIndex=125|IsNotAccesible=T|IndexInSheet=23|OwnerPartId=1|Location.X=869|Location.Y=905|Corner.X=862|Corner.X_Frac=80000|Corner.Y=911|Corner.Y_Frac=30000|LineWidth=1|Color=16711680
|RECORD=13|OwnerIndex=125|IsNotAccesible=T|IndexInSheet=24|OwnerPartId=1|Location.X=850|Location.Y=910|Corner.X=850|Corner.Y=913|Corner.Y_Frac=80000|LineWidth=1|Color=16711680
|RECORD=13|OwnerIndex=125|IsNotAccesible=T|IndexInSheet=25|OwnerPartId=1|Location.X=850|Location.Y=926|Corner.X=850|Corner.Y=929|Corner.Y_Frac=70000|LineWidth=1|Color=16711680
|RECORD=7|OwnerIndex=125|IsNotAccesible=T|IndexInSheet=26|OwnerPartId=1|LineWidth=1|Color=16711680|AreaColor=16711680|IsSolid=T|LocationCount=3|X1=864|Y1=904|X2=862|Y2=902|X3=865|Y3=901
|RECORD=7|OwnerIndex=125|IsNotAccesible=T|IndexInSheet=27|OwnerPartId=1|LineWidth=1|Color=16711680|AreaColor=16711680|IsSolid=T|LocationCount=3|X1=868|Y1=908|X2=866|Y2=906|X3=869|Y3=905
|RECORD=7|OwnerIndex=125|IsNotAccesible=T|IndexInSheet=28|OwnerPartId=1|LineWidth=1|Color=16711680|AreaColor=16777215|IsSolid=T|LocationCount=3|X1=850|Y1=914|X2=858|Y2=926|X3=842|Y3=926
|RECORD=41|OwnerIndex=125|IndexInSheet=29|OwnerPartId=-1|Location.X=837|Location.X_Frac=50000|Location.Y=952|Color=8388608|FontID=1|IsHidden=T|Text=<VALENTIUM>|Name=VALENTIUM PART NUM
|RECORD=34|OwnerIndex=125|IndexInSheet=-1|OwnerPartId=-1|Location.X=870|Location.Y=918|Location.Y_Frac=50000|Color=8388608|FontID=4|Text=D12|Name=Designator|ReadOnlyState=1
|RECORD=41|OwnerIndex=125|IndexInSheet=-1|OwnerPartId=-1|Location.X=837|Location.X_Frac=50000|Location.Y=952|Color=8388608|FontID=3|IsHidden=T|Text==VALUE|Name=Comment|ReadOnlyState=1
|RECORD=44|OwnerIndex=125
|RECORD=45|OwnerIndex=160|IndexInSheet=-1|Description=Molded Diode, 0603, 2-Leads, Body 1.60x0.80mm, IPC Medium Density|UseComponentLibrary=T|ModelName=DIOM1608X06N|ModelType=PCBLIB|DatafileCount=1|ModelDatafileEntity0=DIOM1608X06N|ModelDatafileKind0=PCBLib|IsCurrent=T|DatalinksLocked=T|DatabaseDatalinksLocked=T|IntegratedModel=T|DatabaseModel=T
|RECORD=46|OwnerIndex=161
|RECORD=48|OwnerIndex=161
|RECORD=1|LibReference=SMTLED_RED_0603_SML|ComponentDescription=LED, RED, SML-LX0603, 635NM, 2V, 20MA, 0603|PartCount=2|DisplayModeCount=1|IndexInSheet=39|OwnerPartId=-1|Location.X=750|Location.Y=950|Orientation=3|CurrentPartId=1|LibraryPath=*|SourceLibraryName=Passives.IntLib|TargetFileName=*|AreaColor=11599871|Color=128|PartIDLocked=F|DesignItemId=SMTLED_RED_0603_SML|AllPinCount=2
|RECORD=41|OwnerIndex=164|OwnerPartId=-1|Location.X=737|Location.X_Frac=50000|Location.Y=952|Color=8388608|FontID=3|IsHidden=T|Text=SML-LX0603IW-TR|Name=MFG PART NUM
|RECORD=41|OwnerIndex=164|IndexInSheet=1|OwnerPartId=-1|Location.X=737|Location.X_Frac=50000|Location.Y=952|Color=8388608|FontID=3|IsHidden=T|Text=9/4/2013|Name=MODIFY DATE
|RECORD=41|OwnerIndex=164|IndexInSheet=2|OwnerPartId=-1|Location.X=737|Location.X_Frac=50000|Location.Y=952|Color=8388608|FontID=3|IsHidden=T|Text=LUMEX|Name=MFG NAME
|RECORD=41|OwnerIndex=164|IndexInSheet=3|OwnerPartId=-1|Location.X=737|Location.X_Frac=50000|Location.Y=952|Color=8388608|FontID=3|IsHidden=T|Text=LED|Name=CATEGORY
|RECORD=41|OwnerIndex=164|IndexInSheet=4|OwnerPartId=-1|Location.X=737|Location.X_Frac=50000|Location.Y=952|Color=8388608|FontID=3|IsHidden=T|Name=Date
|RECORD=41|OwnerIndex=164|IndexInSheet=5|OwnerPartId=-1|Location.X=737|Location.X_Frac=50000|Location.Y=952|Color=8388608|FontID=3|IsHidden=T|Text=85C|Name=MAXTEMP
|RECORD=41|OwnerIndex=164|IndexInSheet=6|OwnerPartId=-1|Location.X=737|Location.X_Frac=50000|Location.Y=952|Color=8388608|FontID=3|IsHidden=T|Text=-25C|Name=MINTEMP
|RECORD=41|OwnerIndex=164|IndexInSheet=7|OwnerPartId=-1|Location.X=737|Location.X_Frac=50000|Location.Y=952|Color=8388608|FontID=3|IsHidden=T|Text=SML-LX0603|Name=OTHER
|RECORD=41|OwnerIndex=164|IndexInSheet=8|OwnerPartId=-1|Location.X=737|Location.X_Frac=50000|Location.Y=952|Color=8388608|FontID=3|IsHidden=T|Text=635NM|Name=P1
|RECORD=41|OwnerIndex=164|IndexInSheet=9|OwnerPartId=-1|Location.X=737|Location.X_Frac=50000|Location.Y=952|Color=8388608|FontID=3|IsHidden=T|Text=2V|Name=P2
|RECORD=41|OwnerIndex=164|IndexInSheet=10|OwnerPartId=-1|Location.X=737|Location.X_Frac=50000|Location.Y=952|Color=8388608|FontID=3|IsHidden=T|Text=20MA|Name=P3
|RECORD=41|OwnerIndex=164|IndexInSheet=11|OwnerPartId=-1|Location.X=737|Location.X_Frac=50000|Location.Y=952|Color=8388608|FontID=3|IsHidden=T|Name=SUB
|RECORD=41|OwnerIndex=164|IndexInSheet=12|OwnerPartId=-1|Location.X=737|Location.X_Frac=50000|Location.Y=952|Color=8388608|FontID=3|IsHidden=T|Text=0603|Name=SIZE
|RECORD=41|OwnerIndex=164|IndexInSheet=13|OwnerPartId=-1|Location.X=737|Location.X_Frac=50000|Location.Y=952|Color=8388608|FontID=1|IsHidden=T|Text=*|Name=SHEETPART
|RECORD=41|OwnerIndex=164|IndexInSheet=14|OwnerPartId=-1|Location.X=737|Location.X_Frac=50000|Location.Y=952|Color=8388608|FontID=1|IsHidden=T|Text=LED, RED, SML-LX0603, 635NM, 2V, 20MA, 0603|Name=DESC
|RECORD=41|OwnerIndex=164|IndexInSheet=15|OwnerPartId=-1|Location.X=737|Location.X_Frac=50000|Location.Y=952|Color=8388608|FontID=1|IsHidden=T|Text=Digi-Key|Name=Supplier 1|ReadOnlyState=3
|RECORD=41|OwnerIndex=164|IndexInSheet=16|OwnerPartId=-1|Location.X=737|Location.X_Frac=50000|Location.Y=952|Color=8388608|FontID=1|IsHidden=T|Text=67-1548-1-ND|Name=Supplier Part Number 1|ReadOnlyState=3
|RECORD=41|OwnerIndex=164|IndexInSheet=17|OwnerPartId=-1|Location.X=770|Location.Y=906|Location.Y_Frac=50000|Color=8388608|FontID=3|Text=RED|Name=VALUE
|RECORD=2|OwnerIndex=164|OwnerPartId=1|FormalType=1|Electrical=4|PinConglomerate=33|PinLength=20|Location.X=750|Location.Y=930|Name=A|Designator=2|PinPropagationDelay=0.000000E+000
|RECORD=2|OwnerIndex=164|OwnerPartId=1|FormalType=1|Electrical=4|PinConglomerate=35|PinLength=20|Location.X=750|Location.Y=910|Name=K|Designator=1|PinPropagationDelay=0.000000E+000
|RECORD=12|OwnerIndex=164|IsNotAccesible=T|IndexInSheet=20|OwnerPartId=1|Location.X=750|Location.Y=920|Radius=12|Radius_Frac=50000|LineWidth=1|EndAngle=360.000|Color=16711680
|RECORD=13|OwnerIndex=164|IsNotAccesible=T|IndexInSheet=21|OwnerPartId=1|Location.X=758|Location.Y=914|Corner.X=743|Corner.Y=914|LineWidth=1|Color=16711680
|RECORD=13|OwnerIndex=164|IsNotAccesible=T|IndexInSheet=22|OwnerPartId=1|Location.X=765|Location.Y=901|Corner.X=758|Corner.X_Frac=70000|Corner.Y=907|Corner.Y_Frac=20000|LineWidth=1|Color=16711680
|RECORD=13|OwnerIndex=164|IsNotAccesible=T|IndexInSheet=23|OwnerPartId=1|Location.X=769|Location.Y=905|Corner.X=762|Corner.X_Frac=80000|Corner.Y=911|Corner.Y_Frac=30000|LineWidth=1|Color=16711680
|RECORD=13|OwnerIndex=164|IsNotAccesible=T|IndexInSheet=24|OwnerPartId=1|Location.X=750|Location.Y=910|Corner.X=750|Corner.Y=913|Corner.Y_Frac=80000|LineWidth=1|Color=16711680
|RECORD=13|OwnerIndex=164|IsNotAccesible=T|IndexInSheet=25|OwnerPartId=1|Location.X=750|Location.Y=926|Corner.X=750|Corner.Y=929|Corner.Y_Frac=70000|LineWidth=1|Color=16711680
|RECORD=7|OwnerIndex=164|IsNotAccesible=T|IndexInSheet=26|OwnerPartId=1|LineWidth=1|Color=16711680|AreaColor=16711680|IsSolid=T|LocationCount=3|X1=764|Y1=904|X2=762|Y2=902|X3=765|Y3=901
|RECORD=7|OwnerIndex=164|IsNotAccesible=T|IndexInSheet=27|OwnerPartId=1|LineWidth=1|Color=16711680|AreaColor=16711680|IsSolid=T|LocationCount=3|X1=768|Y1=908|X2=766|Y2=906|X3=769|Y3=905
|RECORD=7|OwnerIndex=164|IsNotAccesible=T|IndexInSheet=28|OwnerPartId=1|LineWidth=1|Color=16711680|AreaColor=16777215|IsSolid=T|LocationCount=3|X1=750|Y1=914|X2=758|Y2=926|X3=742|Y3=926
|RECORD=41|OwnerIndex=164|IndexInSheet=29|OwnerPartId=-1|Location.X=737|Location.X_Frac=50000|Location.Y=952|Color=8388608|FontID=1|IsHidden=T|Text=<VALENTIUM>|Name=VALENTIUM PART NUM
|RECORD=34|OwnerIndex=164|IndexInSheet=-1|OwnerPartId=-1|Location.X=770|Location.Y=918|Location.Y_Frac=50000|Color=8388608|FontID=4|Text=D11|Name=Designator|ReadOnlyState=1
|RECORD=41|OwnerIndex=164|IndexInSheet=-1|OwnerPartId=-1|Location.X=737|Location.X_Frac=50000|Location.Y=952|Color=8388608|FontID=3|IsHidden=T|Text==VALUE|Name=Comment|ReadOnlyState=1
|RECORD=44|OwnerIndex=164
|RECORD=45|OwnerIndex=199|IndexInSheet=-1|Description=Molded Diode, 0603, 2-Leads, Body 1.60x0.80mm, IPC Medium Density|UseComponentLibrary=T|ModelName=DIOM1608X06N|ModelType=PCBLIB|DatafileCount=1|ModelDatafileEntity0=DIOM1608X06N|ModelDatafileKind0=PCBLib|IsCurrent=T|DatalinksLocked=T|DatabaseDatalinksLocked=T|IntegratedModel=T|DatabaseModel=T
|RECORD=46|OwnerIndex=200
|RECORD=48|OwnerIndex=200
|RECORD=4|IndexInSheet=40|OwnerPartId=-1|Location.X=870|Location.Y=1000|Color=8388608|FontID=6|Text=LEDS
|RECORD=17|IndexInSheet=41|OwnerPartId=-1|Style=4|ShowNetName=T|Location.X=1350|Location.Y=470|Orientation=3|Color=128|FontID=1|Text=GND
|RECORD=17|IndexInSheet=42|OwnerPartId=-1|Style=4|ShowNetName=T|Location.X=1350|Location.Y=150|Orientation=3|Color=128|FontID=1|Text=GND
|RECORD=17|IndexInSheet=43|OwnerPartId=-1|Style=4|ShowNetName=T|Location.X=760|Location.Y=120|Orientation=3|Color=128|FontID=1|Text=GND
|RECORD=17|IndexInSheet=44|OwnerPartId=-1|Style=4|ShowNetName=T|Location.X=760|Location.Y=470|Orientation=3|Color=128|FontID=1|Text=GND
|RECORD=17|IndexInSheet=45|OwnerPartId=-1|ShowNetName=T|Location.X=410|Location.Y=570|Orientation=2|Color=255|FontID=1|Text=ANT1|IsCrossSheetConnector=T
|RECORD=17|IndexInSheet=46|OwnerPartId=-1|ShowNetName=T|Location.X=410|Location.Y=220|Orientation=2|Color=255|FontID=1|Text=ANT2|IsCrossSheetConnector=T
|RECORD=17|IndexInSheet=47|OwnerPartId=-1|ShowNetName=T|Location.X=1000|Location.Y=250|Orientation=2|Color=255|FontID=1|Text=ANT4|IsCrossSheetConnector=T
|RECORD=17|IndexInSheet=48|OwnerPartId=-1|ShowNetName=T|Location.X=1000|Location.Y=570|Orientation=2|Color=255|FontID=1|Text=ANT3|IsCrossSheetConnector=T
|RECORD=4|IndexInSheet=49|OwnerPartId=-1|Location.X=490|Location.Y=700|Color=8388608|FontID=6|Text=TIMECARD OUTPUT
|RECORD=1|LibReference=RES|ComponentDescription=ERJ-3EKF2000V|PartCount=2|DisplayModeCount=2|IndexInSheet=50|OwnerPartId=-1|Location.X=740|Location.Y=850|Orientation=1|CurrentPartId=1|SourceLibraryName=Altium Content Vault|TargetFileName=*|AreaColor=11599871|Color=128|PartIDLocked=F|DesignItemId=CMP-2000-00316-1|AllPinCount=2
|RECORD=2|OwnerIndex=213|OwnerPartId=1|OwnerPartDisplayMode=1|FormalType=1|Electrical=4|PinConglomerate=33|PinLength=10|Location.X=750|Location.Y=870|Name=2|Designator=2|PinPropagationDelay=0.000000E+000
|RECORD=2|OwnerIndex=213|OwnerPartId=1|OwnerPartDisplayMode=1|FormalType=1|Electrical=4|PinConglomerate=35|PinLength=10|Location.X=750|Location.Y=850|Name=1|Designator=1|PinPropagationDelay=0.000000E+000
|RECORD=14|OwnerIndex=213|IsNotAccesible=T|IndexInSheet=2|OwnerPartId=1|OwnerPartDisplayMode=1|Location.X=746|Location.Y=850|Corner.X=754|Corner.Y=870|LineWidth=1|Color=16711680|AreaColor=11599871
|RECORD=2|OwnerIndex=213|OwnerPartId=1|FormalType=1|Electrical=4|PinConglomerate=33|PinLength=10|Location.X=750|Location.Y=870|Name=2|Designator=2|PinPropagationDelay=0.000000E+000
|RECORD=2|OwnerIndex=213|OwnerPartId=1|FormalType=1|Electrical=4|PinConglomerate=35|PinLength=10|Location.X=750|Location.Y=850|Name=1|Designator=1|PinPropagationDelay=0.000000E+000
|RECORD=6|OwnerIndex=213|IsNotAccesible=T|IndexInSheet=5|OwnerPartId=1|LineWidth=1|Color=16711680|LocationCount=10|X1=750|Y1=870|X2=750|Y2=866|X3=752|Y3=865|X4=748|Y4=863|X5=752|Y5=861|X6=748|Y6=859|X7=752|Y7=857|X8=748|Y8=855|X9=750|Y9=854|X10=750|Y10=850
|RECORD=41|OwnerIndex=213|IndexInSheet=6|OwnerPartId=-1|Location.X=747|Location.Y=882|Color=8388608|FontID=1|IsHidden=T|Text=Panasonic|Name=Manufacturer
|RECORD=41|OwnerIndex=213|IndexInSheet=7|OwnerPartId=-1|Location.X=747|Location.Y=882|Color=8388608|FontID=1|IsHidden=T|Text=ERJ-3EKF2000V|Name=Part Number
|RECORD=34|OwnerIndex=213|IndexInSheet=-1|OwnerPartId=-1|Location.X=753|Location.Y=861|Color=8388608|FontID=1|Text=R16|Name=Designator|ReadOnlyState=1
|RECORD=41|OwnerIndex=213|IndexInSheet=-1|OwnerPartId=-1|Location.X=753|Location.Y=851|Color=8388608|FontID=1|Text=200 OHM|Name=Comment
|RECORD=44|OwnerIndex=213
|RECORD=45|OwnerIndex=228|IndexInSheet=-1|Description=Chip Resistor, 2-Leads, Body 1.60x0.80mm, IPC Medium Density|UseComponentLibrary=T|ModelName=RESC1608X55X30NL15T15|ModelType=PCBLIB|DatafileCount=1|ModelDatafileEntity0=RESC1608X55X30NL15T15|ModelDatafileKind0=PCBLib|IsCurrent=T|DatalinksLocked=T|DatabaseDatalinksLocked=T
|RECORD=46|OwnerIndex=229
|RECORD=48|OwnerIndex=229
|RECORD=41|OwnerIndex=231|IndexInSheet=-1|OwnerPartId=-1|Color=8388608|FontID=1|Text=2D|Name=Available Preview Images
|RECORD=45|OwnerIndex=228|IndexInSheet=-1|Description=Chip Resistor, 2-Leads, Body 1.60x0.80mm, IPC Low Density|UseComponentLibrary=T|ModelName=RESC1608X55X30ML15T15|ModelType=PCBLIB|DatafileCount=1|ModelDatafileEntity0=RESC1608X55X30ML15T15|ModelDatafileKind0=PCBLib|DatalinksLocked=T|DatabaseDatalinksLocked=T
|RECORD=46|OwnerIndex=233
|RECORD=48|OwnerIndex=233
|RECORD=41|OwnerIndex=235|IndexInSheet=-1|OwnerPartId=-1|Color=8388608|FontID=1|Text=2D|Name=Available Preview Images
|RECORD=45|OwnerIndex=228|IndexInSheet=-1|Description=Chip Resistor, 2-Leads, Body 1.60x0.80mm, IPC High Density|UseComponentLibrary=T|ModelName=RESC1608X55X30LL15T15|ModelType=PCBLIB|DatafileCount=1|ModelDatafileEntity0=RESC1608X55X30LL15T15|ModelDatafileKind0=PCBLib|DatalinksLocked=T|DatabaseDatalinksLocked=T
|RECORD=46|OwnerIndex=237
|RECORD=48|OwnerIndex=237
|RECORD=41|OwnerIndex=239|IndexInSheet=-1|OwnerPartId=-1|Color=8388608|FontID=1|Text=2D|Name=Available Preview Images
|RECORD=1|LibReference=RES|ComponentDescription=ERJ-3EKF2000V|PartCount=2|DisplayModeCount=2|IndexInSheet=51|OwnerPartId=-1|Location.X=840|Location.Y=850|Orientation=1|CurrentPartId=1|SourceLibraryName=Altium Content Vault|TargetFileName=*|AreaColor=11599871|Color=128|PartIDLocked=F|DesignItemId=CMP-2000-00316-1|AllPinCount=2
|RECORD=2|OwnerIndex=241|OwnerPartId=1|OwnerPartDisplayMode=1|FormalType=1|Electrical=4|PinConglomerate=33|PinLength=10|Location.X=850|Location.Y=870|Name=2|Designator=2|PinPropagationDelay=0.000000E+000
|RECORD=2|OwnerIndex=241|OwnerPartId=1|OwnerPartDisplayMode=1|FormalType=1|Electrical=4|PinConglomerate=35|PinLength=10|Location.X=850|Location.Y=850|Name=1|Designator=1|PinPropagationDelay=0.000000E+000
|RECORD=14|OwnerIndex=241|IsNotAccesible=T|IndexInSheet=2|OwnerPartId=1|OwnerPartDisplayMode=1|Location.X=846|Location.Y=850|Corner.X=854|Corner.Y=870|LineWidth=1|Color=16711680|AreaColor=11599871
|RECORD=2|OwnerIndex=241|OwnerPartId=1|FormalType=1|Electrical=4|PinConglomerate=33|PinLength=10|Location.X=850|Location.Y=870|Name=2|Designator=2|PinPropagationDelay=0.000000E+000
|RECORD=2|OwnerIndex=241|OwnerPartId=1|FormalType=1|Electrical=4|PinConglomerate=35|PinLength=10|Location.X=850|Location.Y=850|Name=1|Designator=1|PinPropagationDelay=0.000000E+000
|RECORD=6|OwnerIndex=241|IsNotAccesible=T|IndexInSheet=5|OwnerPartId=1|LineWidth=1|Color=16711680|LocationCount=10|X1=850|Y1=870|X2=850|Y2=866|X3=852|Y3=865|X4=848|Y4=863|X5=852|Y5=861|X6=848|Y6=859|X7=852|Y7=857|X8=848|Y8=855|X9=850|Y9=854|X10=850|Y10=850
|RECORD=41|OwnerIndex=241|IndexInSheet=6|OwnerPartId=-1|Location.X=847|Location.Y=882|Color=8388608|FontID=1|IsHidden=T|Text=Panasonic|Name=Manufacturer
|RECORD=41|OwnerIndex=241|IndexInSheet=7|OwnerPartId=-1|Location.X=847|Location.Y=882|Color=8388608|FontID=1|IsHidden=T|Text=ERJ-3EKF2000V|Name=Part Number
|RECORD=34|OwnerIndex=241|IndexInSheet=-1|OwnerPartId=-1|Location.X=853|Location.Y=861|Color=8388608|FontID=1|Text=R28|Name=Designator|ReadOnlyState=1
|RECORD=41|OwnerIndex=241|IndexInSheet=-1|OwnerPartId=-1|Location.X=853|Location.Y=851|Color=8388608|FontID=1|Text=200 OHM|Name=Comment
|RECORD=44|OwnerIndex=241
|RECORD=45|OwnerIndex=256|IndexInSheet=-1|Description=Chip Resistor, 2-Leads, Body 1.60x0.80mm, IPC Medium Density|UseComponentLibrary=T|ModelName=RESC1608X55X30NL15T15|ModelType=PCBLIB|DatafileCount=1|ModelDatafileEntity0=RESC1608X55X30NL15T15|ModelDatafileKind0=PCBLib|IsCurrent=T|DatalinksLocked=T|DatabaseDatalinksLocked=T
|RECORD=46|OwnerIndex=257
|RECORD=48|OwnerIndex=257
|RECORD=41|OwnerIndex=259|IndexInSheet=-1|OwnerPartId=-1|Color=8388608|FontID=1|Text=2D|Name=Available Preview Images
|RECORD=45|OwnerIndex=256|IndexInSheet=-1|Description=Chip Resistor, 2-Leads, Body 1.60x0.80mm, IPC Low Density|UseComponentLibrary=T|ModelName=RESC1608X55X30ML15T15|ModelType=PCBLIB|DatafileCount=1|ModelDatafileEntity0=RESC1608X55X30ML15T15|ModelDatafileKind0=PCBLib|DatalinksLocked=T|DatabaseDatalinksLocked=T
|RECORD=46|OwnerIndex=261
|RECORD=48|OwnerIndex=261
|RECORD=41|OwnerIndex=263|IndexInSheet=-1|OwnerPartId=-1|Color=8388608|FontID=1|Text=2D|Name=Available Preview Images
|RECORD=45|OwnerIndex=256|IndexInSheet=-1|Description=Chip Resistor, 2-Leads, Body 1.60x0.80mm, IPC High Density|UseComponentLibrary=T|ModelName=RESC1608X55X30LL15T15|ModelType=PCBLIB|DatafileCount=1|ModelDatafileEntity0=RESC1608X55X30LL15T15|ModelDatafileKind0=PCBLib|DatalinksLocked=T|DatabaseDatalinksLocked=T
|RECORD=46|OwnerIndex=265
|RECORD=48|OwnerIndex=265
|RECORD=41|OwnerIndex=267|IndexInSheet=-1|OwnerPartId=-1|Color=8388608|FontID=1|Text=2D|Name=Available Preview Images
|RECORD=1|LibReference=RES|ComponentDescription=ERJ-3EKF2000V|PartCount=2|DisplayModeCount=2|IndexInSheet=52|OwnerPartId=-1|Location.X=940|Location.Y=850|Orientation=1|CurrentPartId=1|SourceLibraryName=Altium Content Vault|TargetFileName=*|AreaColor=11599871|Color=128|PartIDLocked=F|DesignItemId=CMP-2000-00316-1|AllPinCount=2
|RECORD=2|OwnerIndex=269|OwnerPartId=1|OwnerPartDisplayMode=1|FormalType=1|Electrical=4|PinConglomerate=33|PinLength=10|Location.X=950|Location.Y=870|Name=2|Designator=2|PinPropagationDelay=0.000000E+000
|RECORD=2|OwnerIndex=269|OwnerPartId=1|OwnerPartDisplayMode=1|FormalType=1|Electrical=4|PinConglomerate=35|PinLength=10|Location.X=950|Location.Y=850|Name=1|Designator=1|PinPropagationDelay=0.000000E+000
|RECORD=14|OwnerIndex=269|IsNotAccesible=T|IndexInSheet=2|OwnerPartId=1|OwnerPartDisplayMode=1|Location.X=946|Location.Y=850|Corner.X=954|Corner.Y=870|LineWidth=1|Color=16711680|AreaColor=11599871
|RECORD=2|OwnerIndex=269|OwnerPartId=1|FormalType=1|Electrical=4|PinConglomerate=33|PinLength=10|Location.X=950|Location.Y=870|Name=2|Designator=2|PinPropagationDelay=0.000000E+000
|RECORD=2|OwnerIndex=269|OwnerPartId=1|FormalType=1|Electrical=4|PinConglomerate=35|PinLength=10|Location.X=950|Location.Y=850|Name=1|Designator=1|PinPropagationDelay=0.000000E+000
|RECORD=6|OwnerIndex=269|IsNotAccesible=T|IndexInSheet=5|OwnerPartId=1|LineWidth=1|Color=16711680|LocationCount=10|X1=950|Y1=870|X2=950|Y2=866|X3=952|Y3=865|X4=948|Y4=863|X5=952|Y5=861|X6=948|Y6=859|X7=952|Y7=857|X8=948|Y8=855|X9=950|Y9=854|X10=950|Y10=850
|RECORD=41|OwnerIndex=269|IndexInSheet=6|OwnerPartId=-1|Location.X=947|Location.Y=882|Color=8388608|FontID=1|IsHidden=T|Text=Panasonic|Name=Manufacturer
|RECORD=41|OwnerIndex=269|IndexInSheet=7|OwnerPartId=-1|Location.X=947|Location.Y=882|Color=8388608|FontID=1|IsHidden=T|Text=ERJ-3EKF2000V|Name=Part Number
|RECORD=34|OwnerIndex=269|IndexInSheet=-1|OwnerPartId=-1|Location.X=953|Location.Y=861|Color=8388608|FontID=1|Text=R29|Name=Designator|ReadOnlyState=1
|RECORD=41|OwnerIndex=269|IndexInSheet=-1|OwnerPartId=-1|Location.X=953|Location.Y=851|Color=8388608|FontID=1|Text=200 OHM|Name=Comment
|RECORD=44|OwnerIndex=269
|RECORD=45|OwnerIndex=284|IndexInSheet=-1|Description=Chip Resistor, 2-Leads, Body 1.60x0.80mm, IPC Medium Density|UseComponentLibrary=T|ModelName=RESC1608X55X30NL15T15|ModelType=PCBLIB|DatafileCount=1|ModelDatafileEntity0=RESC1608X55X30NL15T15|ModelDatafileKind0=PCBLib|IsCurrent=T|DatalinksLocked=T|DatabaseDatalinksLocked=T
|RECORD=46|OwnerIndex=285
|RECORD=48|OwnerIndex=285
|RECORD=41|OwnerIndex=287|IndexInSheet=-1|OwnerPartId=-1|Color=8388608|FontID=1|Text=2D|Name=Available Preview Images
|RECORD=45|OwnerIndex=284|IndexInSheet=-1|Description=Chip Resistor, 2-Leads, Body 1.60x0.80mm, IPC Low Density|UseComponentLibrary=T|ModelName=RESC1608X55X30ML15T15|ModelType=PCBLIB|DatafileCount=1|ModelDatafileEntity0=RESC1608X55X30ML15T15|ModelDatafileKind0=PCBLib|DatalinksLocked=T|DatabaseDatalinksLocked=T
|RECORD=46|OwnerIndex=289
|RECORD=48|OwnerIndex=289
|RECORD=41|OwnerIndex=291|IndexInSheet=-1|OwnerPartId=-1|Color=8388608|FontID=1|Text=2D|Name=Available Preview Images
|RECORD=45|OwnerIndex=284|IndexInSheet=-1|Description=Chip Resistor, 2-Leads, Body 1.60x0.80mm, IPC High Density|UseComponentLibrary=T|ModelName=RESC1608X55X30LL15T15|ModelType=PCBLIB|DatafileCount=1|ModelDatafileEntity0=RESC1608X55X30LL15T15|ModelDatafileKind0=PCBLib|DatalinksLocked=T|DatabaseDatalinksLocked=T
|RECORD=46|OwnerIndex=293
|RECORD=48|OwnerIndex=293
|RECORD=41|OwnerIndex=295|IndexInSheet=-1|OwnerPartId=-1|Color=8388608|FontID=1|Text=2D|Name=Available Preview Images
|RECORD=1|LibReference=RES|ComponentDescription=ERJ-3EKF2000V|PartCount=2|DisplayModeCount=2|IndexInSheet=53|OwnerPartId=-1|Location.X=1040|Location.Y=850|Orientation=1|CurrentPartId=1|SourceLibraryName=Altium Content Vault|TargetFileName=*|AreaColor=11599871|Color=128|PartIDLocked=F|DesignItemId=CMP-2000-00316-1|AllPinCount=2
|RECORD=2|OwnerIndex=297|OwnerPartId=1|OwnerPartDisplayMode=1|FormalType=1|Electrical=4|PinConglomerate=33|PinLength=10|Location.X=1050|Location.Y=870|Name=2|Designator=2|PinPropagationDelay=0.000000E+000
|RECORD=2|OwnerIndex=297|OwnerPartId=1|OwnerPartDisplayMode=1|FormalType=1|Electrical=4|PinConglomerate=35|PinLength=10|Location.X=1050|Location.Y=850|Name=1|Designator=1|PinPropagationDelay=0.000000E+000
|RECORD=14|OwnerIndex=297|IsNotAccesible=T|IndexInSheet=2|OwnerPartId=1|OwnerPartDisplayMode=1|Location.X=1046|Location.Y=850|Corner.X=1054|Corner.Y=870|LineWidth=1|Color=16711680|AreaColor=11599871
|RECORD=2|OwnerIndex=297|OwnerPartId=1|FormalType=1|Electrical=4|PinConglomerate=33|PinLength=10|Location.X=1050|Location.Y=870|Name=2|Designator=2|PinPropagationDelay=0.000000E+000
|RECORD=2|OwnerIndex=297|OwnerPartId=1|FormalType=1|Electrical=4|PinConglomerate=35|PinLength=10|Location.X=1050|Location.Y=850|Name=1|Designator=1|PinPropagationDelay=0.000000E+000
|RECORD=6|OwnerIndex=297|IsNotAccesible=T|IndexInSheet=5|OwnerPartId=1|LineWidth=1|Color=16711680|LocationCount=10|X1=1050|Y1=870|X2=1050|Y2=866|X3=1052|Y3=865|X4=1048|Y4=863|X5=1052|Y5=861|X6=1048|Y6=859|X7=1052|Y7=857|X8=1048|Y8=855|X9=1050|Y9=854|X10=1050|Y10=850
|RECORD=41|OwnerIndex=297|IndexInSheet=6|OwnerPartId=-1|Location.X=1047|Location.Y=882|Color=8388608|FontID=1|IsHidden=T|Text=Panasonic|Name=Manufacturer
|RECORD=41|OwnerIndex=297|IndexInSheet=7|OwnerPartId=-1|Location.X=1047|Location.Y=882|Color=8388608|FontID=1|IsHidden=T|Text=ERJ-3EKF2000V|Name=Part Number
|RECORD=34|OwnerIndex=297|IndexInSheet=-1|OwnerPartId=-1|Location.X=1053|Location.Y=861|Color=8388608|FontID=1|Text=R30|Name=Designator|ReadOnlyState=1
|RECORD=41|OwnerIndex=297|IndexInSheet=-1|OwnerPartId=-1|Location.X=1053|Location.Y=851|Color=8388608|FontID=1|Text=200 OHM|Name=Comment
|RECORD=44|OwnerIndex=297
|RECORD=45|OwnerIndex=312|IndexInSheet=-1|Description=Chip Resistor, 2-Leads, Body 1.60x0.80mm, IPC Medium Density|UseComponentLibrary=T|ModelName=RESC1608X55X30NL15T15|ModelType=PCBLIB|DatafileCount=1|ModelDatafileEntity0=RESC1608X55X30NL15T15|ModelDatafileKind0=PCBLib|IsCurrent=T|DatalinksLocked=T|DatabaseDatalinksLocked=T
|RECORD=46|OwnerIndex=313
|RECORD=48|OwnerIndex=313
|RECORD=41|OwnerIndex=315|IndexInSheet=-1|OwnerPartId=-1|Color=8388608|FontID=1|Text=2D|Name=Available Preview Images
|RECORD=45|OwnerIndex=312|IndexInSheet=-1|Description=Chip Resistor, 2-Leads, Body 1.60x0.80mm, IPC Low Density|UseComponentLibrary=T|ModelName=RESC1608X55X30ML15T15|ModelType=PCBLIB|DatafileCount=1|ModelDatafileEntity0=RESC1608X55X30ML15T15|ModelDatafileKind0=PCBLib|DatalinksLocked=T|DatabaseDatalinksLocked=T
|RECORD=46|OwnerIndex=317
|RECORD=48|OwnerIndex=317
|RECORD=41|OwnerIndex=319|IndexInSheet=-1|OwnerPartId=-1|Color=8388608|FontID=1|Text=2D|Name=Available Preview Images
|RECORD=45|OwnerIndex=312|IndexInSheet=-1|Description=Chip Resistor, 2-Leads, Body 1.60x0.80mm, IPC High Density|UseComponentLibrary=T|ModelName=RESC1608X55X30LL15T15|ModelType=PCBLIB|DatafileCount=1|ModelDatafileEntity0=RESC1608X55X30LL15T15|ModelDatafileKind0=PCBLib|DatalinksLocked=T|DatabaseDatalinksLocked=T
|RECORD=46|OwnerIndex=321
|RECORD=48|OwnerIndex=321
|RECORD=41|OwnerIndex=323|IndexInSheet=-1|OwnerPartId=-1|Color=8388608|FontID=1|Text=2D|Name=Available Preview Images
|RECORD=1|LibReference=CN-1P-M-RF3|ComponentDescription=Ultra Miniature Coaxial Connector Jack, 60 V, 50 Ohm, -40 to 90 degC, RoHS, Tape and Reel|PartCount=2|DisplayModeCount=1|IndexInSheet=54|OwnerPartId=-1|Location.X=720|Location.Y=680|CurrentPartId=1|LibraryPath=*|SourceLibraryName=Altium Content Vault|TargetFileName=*|AreaColor=11599871|Color=128|PartIDLocked=T|DesignItemId=CMP-2000-07505-1|AllPinCount=3
|RECORD=8|OwnerIndex=325|IsNotAccesible=T|OwnerPartId=1|Location.X=740|Location.Y=660|Radius=20|SecondaryRadius=20|LineWidth=1|Color=16711680|AreaColor=16777215
|RECORD=8|OwnerIndex=325|IsNotAccesible=T|IndexInSheet=1|OwnerPartId=1|Location.X=740|Location.Y=660|Radius=4|SecondaryRadius=4|LineWidth=1|Color=16711680|AreaColor=16777215
|RECORD=2|OwnerIndex=325|OwnerPartId=1|FormalType=1|Electrical=4|PinConglomerate=51|PinLength=10|Location.X=730|Location.Y=640|Name=1|Designator=1|PinPropagationDelay=0.000000E+000
|RECORD=2|OwnerIndex=325|OwnerPartId=1|FormalType=1|Electrical=4|PinConglomerate=50|PinLength=10|Location.X=720|Location.Y=660|Name=2|Designator=2|PinPropagationDelay=0.000000E+000
|RECORD=2|OwnerIndex=325|OwnerPartId=1|FormalType=1|Electrical=4|PinConglomerate=51|PinLength=10|Location.X=750|Location.Y=640|Name=3|Designator=3|PinPropagationDelay=0.000000E+000
|RECORD=6|OwnerIndex=325|IsNotAccesible=T|IndexInSheet=5|OwnerPartId=1|LineWidth=1|Color=16711680|LocationCount=5|X1=720|Y1=640|X2=720|Y2=680|X3=760|Y3=680|X4=760|Y4=640|X5=720|Y5=640
|RECORD=6|OwnerIndex=325|IsNotAccesible=T|IndexInSheet=6|OwnerPartId=1|LineWidth=1|Color=16711680|LocationCount=2|X1=720|Y1=660|X2=736|Y2=660
|RECORD=41|OwnerIndex=325|IndexInSheet=7|OwnerPartId=-1|Location.X=708|Location.Y=681|Color=8388608|FontID=1|IsHidden=T|Text=Straight|Name=Orientation
|RECORD=41|OwnerIndex=325|IndexInSheet=8|OwnerPartId=-1|Location.X=708|Location.Y=681|Color=8388608|FontID=1|IsHidden=T|Text=Female|Name=Gender
|RECORD=41|OwnerIndex=325|IndexInSheet=9|OwnerPartId=-1|Location.X=708|Location.Y=681|Color=8388608|FontID=1|IsHidden=T|Text=Vertical|Name=PCB Mounting Orientation
|RECORD=41|OwnerIndex=325|IndexInSheet=10|OwnerPartId=-1|Location.X=708|Location.Y=681|Color=8388608|FontID=1|IsHidden=T|Text=SurfaceMount|Name=Mount
|RECORD=41|OwnerIndex=325|IndexInSheet=11|OwnerPartId=-1|Location.X=708|Location.Y=681|Color=8388608|FontID=1|IsHidden=T|Text=3mm|Name=Length
|RECORD=41|OwnerIndex=325|IndexInSheet=12|OwnerPartId=-1|Location.X=708|Location.Y=681|Color=8388608|FontID=1|IsHidden=T|Text=TapeandReel|Name=Packaging
|RECORD=41|OwnerIndex=325|IndexInSheet=13|OwnerPartId=-1|Location.X=708|Location.Y=681|Color=8388608|FontID=1|IsHidden=T|Text=Jack|Name=Connector Type
|RECORD=41|OwnerIndex=325|IndexInSheet=14|OwnerPartId=-1|Location.X=708|Location.Y=681|Color=8388608|FontID=1|IsHidden=T|Text=LeadFree|Name=Lead Free
|RECORD=41|OwnerIndex=325|IndexInSheet=15|OwnerPartId=-1|Location.X=708|Location.Y=681|Color=8388608|FontID=1|IsHidden=T|Text=1|Name=Package Quantity
|RECORD=41|OwnerIndex=325|IndexInSheet=16|OwnerPartId=-1|Location.X=708|Location.Y=681|Color=8388608|FontID=1|IsHidden=T|Text=SMD/SMT|Name=Termination
|RECORD=41|OwnerIndex=325|IndexInSheet=17|OwnerPartId=-1|Location.X=708|Location.Y=681|Color=8388608|FontID=1|IsHidden=T|Text=CopperAlloy|Name=Contact Material
|RECORD=41|OwnerIndex=325|IndexInSheet=18|OwnerPartId=-1|Location.X=708|Location.Y=681|Color=8388608|FontID=1|IsHidden=T|Text=Pull|Name=Fastening Type
|RECORD=41|OwnerIndex=325|IndexInSheet=19|OwnerPartId=-1|Location.X=708|Location.Y=681|Color=8388608|FontID=1|IsHidden=T|Text=true|Name=RoHSCompliant
|RECORD=41|OwnerIndex=325|IndexInSheet=20|OwnerPartId=-1|Location.X=708|Location.Y=681|Color=8388608|FontID=1|IsHidden=T|Text=LiquidCrystalPolymer|Name=Body Material
|RECORD=41|OwnerIndex=325|IndexInSheet=21|OwnerPartId=-1|Location.X=708|Location.Y=681|Color=8388608|FontID=1|IsHidden=T|Text=SMD/SMT|Name=Case\/Package
|RECORD=41|OwnerIndex=325|IndexInSheet=22|OwnerPartId=-1|Location.X=708|Location.Y=681|Color=8388608|FontID=1|IsHidden=T|Text=90degC|Name=Max Operating Temperature
|RECORD=41|OwnerIndex=325|IndexInSheet=23|OwnerPartId=-1|Location.X=708|Location.Y=681|Color=8388608|FontID=1|IsHidden=T|Text=50Ohm|Name=Impedance
|RECORD=41|OwnerIndex=325|IndexInSheet=24|OwnerPartId=-1|Location.X=708|Location.Y=681|Color=8388608|FontID=2|IsHidden=T|Text=http://www.te.com/commerce/DocumentDelivery/DDEController?Action=srchrtrv&DocNm=1909763&DocType=Customer+Drawing&DocLang=English|Name=Datasheet URL
|RECORD=41|OwnerIndex=325|IndexInSheet=25|OwnerPartId=-1|Location.X=708|Location.Y=681|Color=8388608|FontID=1|IsHidden=T|Text=Gold|Name=Contact Plating
|RECORD=41|OwnerIndex=325|IndexInSheet=26|OwnerPartId=-1|Location.X=708|Location.Y=681|Color=8388608|FontID=1|IsHidden=T|Text=SurfaceMount|Name=Mounting Technology
|RECORD=41|OwnerIndex=325|IndexInSheet=27|OwnerPartId=-1|Location.X=708|Location.Y=681|Color=8388608|FontID=1|IsHidden=T|Text=6GHz|Name=Max Frequency
|RECORD=41|OwnerIndex=325|IndexInSheet=28|OwnerPartId=-1|Location.X=708|Location.Y=681|Color=8388608|FontID=1|IsHidden=T|Text=TECO-1909763-1|Name=Package Reference
|RECORD=41|OwnerIndex=325|IndexInSheet=29|OwnerPartId=-1|Location.X=708|Location.Y=681|Color=8388608|FontID=1|IsHidden=T|Text=Thermoplastic|Name=Insulation Material
|RECORD=41|OwnerIndex=325|IndexInSheet=30|OwnerPartId=-1|Location.X=708|Location.Y=681|Color=8388608|FontID=1|IsHidden=T|Text=-40degC|Name=Min Operating Temperature
|RECORD=41|OwnerIndex=325|IndexInSheet=31|OwnerPartId=-1|Location.X=708|Location.Y=681|Color=8388608|FontID=2|IsHidden=T|Text=http://www.te.com/|Name=Manufacturer URL
|RECORD=41|OwnerIndex=325|IndexInSheet=32|OwnerPartId=-1|Location.X=708|Location.Y=681|Color=8388608|FontID=1|IsHidden=T|Text=Gold|Name=Body Plating
|RECORD=41|OwnerIndex=325|IndexInSheet=33|OwnerPartId=-1|Location.X=708|Location.Y=681|Color=8388608|FontID=1|IsHidden=T|Text=Polymer|Name=Dielectric Material
|RECORD=41|OwnerIndex=325|IndexInSheet=34|OwnerPartId=-1|Location.X=708|Location.Y=681|Color=8388608|FontID=1|IsHidden=T|Text=TE Connectivity|Name=Manufacturer
|RECORD=41|OwnerIndex=325|IndexInSheet=35|OwnerPartId=-1|Location.X=708|Location.Y=681|Color=8388608|FontID=1|IsHidden=T|Text=Compliant|Name=ELV
|RECORD=41|OwnerIndex=325|IndexInSheet=36|OwnerPartId=-1|Location.X=708|Location.Y=681|Color=8388608|FontID=1|IsHidden=T|Text=Rev. B2, 11/2015|Name=Datasheet Version
|RECORD=41|OwnerIndex=325|IndexInSheet=37|OwnerPartId=-1|Location.X=708|Location.Y=681|Color=8388608|FontID=1|IsHidden=T|Text=No|Name=Radiation Hardening
|RECORD=41|OwnerIndex=325|IndexInSheet=38|OwnerPartId=-1|Location.X=708|Location.Y=681|Color=8388608|FontID=1|IsHidden=T|Text=3-Pin Surface Mount Device, Body 2.6 x 2.6 mm|Name=Package Description
|RECORD=41|OwnerIndex=325|IndexInSheet=39|OwnerPartId=-1|Location.X=708|Location.Y=681|Color=8388608|FontID=1|IsHidden=T|Text=Beige|Name=Housing Colour
|RECORD=34|OwnerIndex=325|IndexInSheet=-1|OwnerPartId=-1|Location.X=719|Location.Y=681|Color=8388608|FontID=1|Text=J6|Name=Designator|ReadOnlyState=1
|RECORD=41|OwnerIndex=325|IndexInSheet=-1|OwnerPartId=-1|Location.X=719|Location.Y=618|Color=8388608|FontID=1|Text=1909763-1|Name=Comment
|RECORD=44|OwnerIndex=325
|RECORD=45|OwnerIndex=371|IndexInSheet=-1|Description=SMD, 3-Leads, Body 2.6x2.6mm, Height 1.25mm|UseComponentLibrary=T|ModelName=TECO-1909763-1_V|ModelType=PCBLIB|DatafileCount=1|ModelDatafileEntity0=TECO-1909763-1_V|ModelDatafileKind0=PCBLib|IsCurrent=T|DatalinksLocked=T|DatabaseDatalinksLocked=T
|RECORD=46|OwnerIndex=372
|RECORD=48|OwnerIndex=372
|RECORD=41|OwnerIndex=374|IndexInSheet=-1|OwnerPartId=-1|Color=8388608|FontID=1|Text=2D|Name=Available Preview Images
|RECORD=1|LibReference=CN-S-4F-RF5|ComponentDescription=Coaxial connector, 50 Ohm, -65 to 165 degC, 5-Pin THD, RoHS, Bulk|PartCount=2|DisplayModeCount=1|IndexInSheet=55|OwnerPartId=-1|Location.X=720|Location.Y=590|CurrentPartId=1|LibraryPath=*|SourceLibraryName=Altium Content Vault|TargetFileName=*|AreaColor=11599871|Color=128|PartIDLocked=T|DesignItemId=CMP-2000-05705-1|AllPinCount=5
|RECORD=2|OwnerIndex=376|OwnerPartId=1|FormalType=1|Electrical=4|PinConglomerate=51|PinLength=10|Location.X=760|Location.Y=550|Name=5|Designator=5|SwapIDPart=Ž&Ž1|PinPropagationDelay=0.000000E+000
|RECORD=8|OwnerIndex=376|IsNotAccesible=T|IndexInSheet=1|OwnerPartId=1|Location.X=740|Location.Y=570|Radius=20|SecondaryRadius=20|LineWidth=1|Color=16711680|AreaColor=16777215
|RECORD=8|OwnerIndex=376|IsNotAccesible=T|IndexInSheet=2|OwnerPartId=1|Location.X=740|Location.Y=570|Radius=4|SecondaryRadius=4|LineWidth=1|Color=16711680|AreaColor=16777215
|RECORD=2|OwnerIndex=376|OwnerPartId=1|FormalType=1|Electrical=4|PinConglomerate=50|PinLength=10|Location.X=720|Location.Y=570|Name=1|Designator=1|PinPropagationDelay=0.000000E+000
|RECORD=2|OwnerIndex=376|OwnerPartId=1|FormalType=1|Electrical=4|PinConglomerate=51|PinLength=10|Location.X=730|Location.Y=550|Name=2|Designator=2|PinPropagationDelay=0.000000E+000
|RECORD=2|OwnerIndex=376|OwnerPartId=1|FormalType=1|Electrical=4|PinConglomerate=51|PinLength=10|Location.X=740|Location.Y=550|Name=3|Designator=3|PinPropagationDelay=0.000000E+000
|RECORD=2|OwnerIndex=376|OwnerPartId=1|FormalType=1|Electrical=4|PinConglomerate=51|PinLength=10|Location.X=750|Location.Y=550|Name=4|Designator=4|PinPropagationDelay=0.000000E+000
|RECORD=6|OwnerIndex=376|IsNotAccesible=T|IndexInSheet=7|OwnerPartId=1|LineWidth=1|Color=16711680|LocationCount=5|X1=720|Y1=550|X2=720|Y2=590|X3=760|Y3=590|X4=760|Y4=550|X5=720|Y5=550
|RECORD=6|OwnerIndex=376|IsNotAccesible=T|IndexInSheet=8|OwnerPartId=1|LineWidth=1|Color=16711680|LocationCount=2|X1=720|Y1=570|X2=736|Y2=570
|RECORD=41|OwnerIndex=376|IndexInSheet=9|OwnerPartId=-1|Location.X=708|Location.Y=591|Color=8388608|FontID=1|IsHidden=T|Text=ThroughHole|Name=Mounting Technology
|RECORD=41|OwnerIndex=376|IndexInSheet=10|OwnerPartId=-1|Location.X=708|Location.Y=591|Color=8388608|FontID=1|IsHidden=T|Text=ThroughHole,RightAngle|Name=Mounting Type
|RECORD=41|OwnerIndex=376|IndexInSheet=11|OwnerPartId=-1|Location.X=708|Location.Y=591|Color=8388608|FontID=1|IsHidden=T|Text=-|Name=Cable Group
|RECORD=41|OwnerIndex=376|IndexInSheet=12|OwnerPartId=-1|Location.X=708|Location.Y=591|Color=8388608|FontID=1|IsHidden=T|Text=901-143-6RFXMountingHole|Name=Catalog Drawings
|RECORD=41|OwnerIndex=376|IndexInSheet=13|OwnerPartId=-1|Location.X=708|Location.Y=591|Color=8388608|FontID=1|IsHidden=T|Text=901-143-6RFX.igs|Name=3D Model
|RECORD=41|OwnerIndex=376|IndexInSheet=14|OwnerPartId=-1|Location.X=708|Location.Y=591|Color=8388608|FontID=1|IsHidden=T|Text=-|Name=Series
|RECORD=41|OwnerIndex=376|IndexInSheet=15|OwnerPartId=-1|Location.X=708|Location.Y=591|Color=8388608|FontID=1|IsHidden=T|Text=5-Pin Through Hole Device, Body 7 x 7 mm, Pitch 2.54 mm|Name=Package Description
|RECORD=41|OwnerIndex=376|IndexInSheet=16|OwnerPartId=-1|Location.X=708|Location.Y=591|Color=8388608|FontID=1|IsHidden=T|Text=901-143-6RFX|Name=Package Reference
|RECORD=41|OwnerIndex=376|IndexInSheet=17|OwnerPartId=-1|Location.X=708|Location.Y=591|Color=8388608|FontID=1|IsHidden=T|Text=Brass|Name=Body Material
|RECORD=41|OwnerIndex=376|IndexInSheet=18|OwnerPartId=-1|Location.X=708|Location.Y=591|Color=8388608|FontID=1|IsHidden=T|Text=-|Name=Voltage Rating
|RECORD=41|OwnerIndex=376|IndexInSheet=19|OwnerPartId=-1|Location.X=708|Location.Y=591|Color=8388608|FontID=1|IsHidden=T|Text=1|Name=Standard Package
|RECORD=41|OwnerIndex=376|IndexInSheet=20|OwnerPartId=-1|Location.X=708|Location.Y=591|Color=8388608|FontID=1|IsHidden=T|Text=Jack,FemaleSocket|Name=Connector Type
|RECORD=41|OwnerIndex=376|IndexInSheet=21|OwnerPartId=-1|Location.X=708|Location.Y=591|Color=8388608|FontID=1|IsHidden=T|Text=Threaded|Name=Fastening Type
|RECORD=41|OwnerIndex=376|IndexInSheet=22|OwnerPartId=-1|Location.X=708|Location.Y=591|Color=8388608|FontID=1|IsHidden=T|Text=Gold|Name=Housing Color
|RECORD=41|OwnerIndex=376|IndexInSheet=23|OwnerPartId=-1|Location.X=708|Location.Y=591|Color=8388608|FontID=1|IsHidden=T|Text=Solder|Name=Shield Termination
|RECORD=41|OwnerIndex=376|IndexInSheet=24|OwnerPartId=-1|Location.X=708|Location.Y=591|Color=8388608|FontID=1|IsHidden=T|Text=901-143-6-RFX9011436RFXARFX1232|Name=Other Names
|RECORD=41|OwnerIndex=376|IndexInSheet=25|OwnerPartId=-1|Location.X=708|Location.Y=591|Color=8388608|FontID=2|IsHidden=T|Text=http://www.amphenolrf.com/downloads/dl/file/id/2712/product/3102/901_143_6rfx_customer_drawing.pdf|Name=Datasheet URL
|RECORD=41|OwnerIndex=376|IndexInSheet=26|OwnerPartId=-1|Location.X=708|Location.Y=591|Color=8388608|FontID=1|IsHidden=T|Text=CoaxialConnectors(RF)|Name=Family
|RECORD=41|OwnerIndex=376|IndexInSheet=27|OwnerPartId=-1|Location.X=708|Location.Y=591|Color=8388608|FontID=1|IsHidden=T|Text=SMA,RFX|Name=Online Catalog
|RECORD=41|OwnerIndex=376|IndexInSheet=28|OwnerPartId=-1|Location.X=708|Location.Y=591|Color=8388608|FontID=1|IsHidden=T|Text=18GHz|Name=Frequency - Max
|RECORD=41|OwnerIndex=376|IndexInSheet=29|OwnerPartId=-1|Location.X=708|Location.Y=591|Color=8388608|FontID=1|IsHidden=T|Text=Solder|Name=Contact Termination
|RECORD=41|OwnerIndex=376|IndexInSheet=30|OwnerPartId=-1|Location.X=708|Location.Y=591|Color=8388608|FontID=2|IsHidden=T|Text=http://www.amphenol.com/|Name=Manufacturer URL
|RECORD=41|OwnerIndex=376|IndexInSheet=31|OwnerPartId=-1|Location.X=708|Location.Y=591|Color=8388608|FontID=1|IsHidden=T|Text=Amphenol|Name=Manufacturer
|RECORD=41|OwnerIndex=376|IndexInSheet=32|OwnerPartId=-1|Location.X=708|Location.Y=591|Color=8388608|FontID=1|IsHidden=T|Text=-65°C~165°C|Name=Operating Temperature
|RECORD=41|OwnerIndex=376|IndexInSheet=33|OwnerPartId=-1|Location.X=708|Location.Y=591|Color=8388608|FontID=1|IsHidden=T|Text=Connectors,Interconnects|Name=Category
|RECORD=41|OwnerIndex=376|IndexInSheet=34|OwnerPartId=-1|Location.X=708|Location.Y=591|Color=8388608|FontID=1|IsHidden=T|Text=Bulk|Name=Packaging
|RECORD=41|OwnerIndex=376|IndexInSheet=35|OwnerPartId=-1|Location.X=708|Location.Y=591|Color=8388608|FontID=1|IsHidden=T|Text=Gold|Name=Body Finish
|RECORD=41|OwnerIndex=376|IndexInSheet=36|OwnerPartId=-1|Location.X=708|Location.Y=591|Color=8388608|FontID=1|IsHidden=T|Text=Polytetrafluoroethylene(PTFE)|Name=Dielectric Material
|RECORD=41|OwnerIndex=376|IndexInSheet=37|OwnerPartId=-1|Location.X=708|Location.Y=591|Color=8388608|FontID=1|IsHidden=T|Text=BerylliumCopper|Name=Center Contact Material
|RECORD=41|OwnerIndex=376|IndexInSheet=38|OwnerPartId=-1|Location.X=708|Location.Y=591|Color=8388608|FontID=1|IsHidden=T|Text=50Ohm|Name=Impedance
|RECORD=41|OwnerIndex=376|IndexInSheet=39|OwnerPartId=-1|Location.X=708|Location.Y=591|Color=8388608|FontID=1|IsHidden=T|Text=-|Name=Features
|RECORD=41|OwnerIndex=376|IndexInSheet=40|OwnerPartId=-1|Location.X=708|Location.Y=591|Color=8388608|FontID=1|IsHidden=T|Text=SMA|Name=Connector Style
|RECORD=41|OwnerIndex=376|IndexInSheet=41|OwnerPartId=-1|Location.X=708|Location.Y=591|Color=8388608|FontID=1|IsHidden=T|Text=Gold|Name=Center Contact Plating
|RECORD=41|OwnerIndex=376|IndexInSheet=42|OwnerPartId=-1|Location.X=708|Location.Y=591|Color=8388608|FontID=1|IsHidden=T|Text=Rev. C, 06/2010|Name=Datasheet Version
|RECORD=41|OwnerIndex=376|IndexInSheet=43|OwnerPartId=-1|Location.X=708|Location.Y=591|Color=8388608|FontID=1|IsHidden=T|Text=-|Name=Ingress Protection
|RECORD=34|OwnerIndex=376|IndexInSheet=-1|OwnerPartId=-1|Location.X=719|Location.Y=591|Color=8388608|FontID=1|Text=AN1|Name=Designator|ReadOnlyState=1
|RECORD=41|OwnerIndex=376|IndexInSheet=-1|OwnerPartId=-1|Location.X=719|Location.Y=528|Color=8388608|FontID=1|Text=901-143-6RFX|Name=Comment
|RECORD=44|OwnerIndex=376
|RECORD=45|OwnerIndex=428|IndexInSheet=-1|Description=THD, 5-Leads, Body 7x7mm, Pitch 2.54mm|UseComponentLibrary=T|ModelName=AMPH-901-143-6RFX_V|ModelType=PCBLIB|DatafileCount=1|ModelDatafileEntity0=AMPH-901-143-6RFX_V|ModelDatafileKind0=PCBLib|IsCurrent=T|DatalinksLocked=T|DatabaseDatalinksLocked=T
|RECORD=46|OwnerIndex=429
|RECORD=48|OwnerIndex=429
|RECORD=41|OwnerIndex=431|IndexInSheet=-1|OwnerPartId=-1|Color=8388608|FontID=1|Text=2D|Name=Available Preview Images
|RECORD=1|LibReference=CN-1P-M-RF3|ComponentDescription=Ultra Miniature Coaxial Connector Jack, 60 V, 50 Ohm, -40 to 90 degC, RoHS, Tape and Reel|PartCount=2|DisplayModeCount=1|IndexInSheet=56|OwnerPartId=-1|Location.X=720|Location.Y=330|CurrentPartId=1|LibraryPath=*|SourceLibraryName=Altium Content Vault|TargetFileName=*|AreaColor=11599871|Color=128|PartIDLocked=T|DesignItemId=CMP-2000-07505-1|AllPinCount=3
|RECORD=8|OwnerIndex=433|IsNotAccesible=T|OwnerPartId=1|Location.X=740|Location.Y=310|Radius=20|SecondaryRadius=20|LineWidth=1|Color=16711680|AreaColor=16777215
|RECORD=8|OwnerIndex=433|IsNotAccesible=T|IndexInSheet=1|OwnerPartId=1|Location.X=740|Location.Y=310|Radius=4|SecondaryRadius=4|LineWidth=1|Color=16711680|AreaColor=16777215
|RECORD=2|OwnerIndex=433|OwnerPartId=1|FormalType=1|Electrical=4|PinConglomerate=51|PinLength=10|Location.X=730|Location.Y=290|Name=1|Designator=1|PinPropagationDelay=0.000000E+000
|RECORD=2|OwnerIndex=433|OwnerPartId=1|FormalType=1|Electrical=4|PinConglomerate=50|PinLength=10|Location.X=720|Location.Y=310|Name=2|Designator=2|PinPropagationDelay=0.000000E+000
|RECORD=2|OwnerIndex=433|OwnerPartId=1|FormalType=1|Electrical=4|PinConglomerate=51|PinLength=10|Location.X=750|Location.Y=290|Name=3|Designator=3|PinPropagationDelay=0.000000E+000
|RECORD=6|OwnerIndex=433|IsNotAccesible=T|IndexInSheet=5|OwnerPartId=1|LineWidth=1|Color=16711680|LocationCount=5|X1=720|Y1=290|X2=720|Y2=330|X3=760|Y3=330|X4=760|Y4=290|X5=720|Y5=290
|RECORD=6|OwnerIndex=433|IsNotAccesible=T|IndexInSheet=6|OwnerPartId=1|LineWidth=1|Color=16711680|LocationCount=2|X1=720|Y1=310|X2=736|Y2=310
|RECORD=41|OwnerIndex=433|IndexInSheet=7|OwnerPartId=-1|Location.X=708|Location.Y=331|Color=8388608|FontID=1|IsHidden=T|Text=Straight|Name=Orientation
|RECORD=41|OwnerIndex=433|IndexInSheet=8|OwnerPartId=-1|Location.X=708|Location.Y=331|Color=8388608|FontID=1|IsHidden=T|Text=Female|Name=Gender
|RECORD=41|OwnerIndex=433|IndexInSheet=9|OwnerPartId=-1|Location.X=708|Location.Y=331|Color=8388608|FontID=1|IsHidden=T|Text=Vertical|Name=PCB Mounting Orientation
|RECORD=41|OwnerIndex=433|IndexInSheet=10|OwnerPartId=-1|Location.X=708|Location.Y=331|Color=8388608|FontID=1|IsHidden=T|Text=SurfaceMount|Name=Mount
|RECORD=41|OwnerIndex=433|IndexInSheet=11|OwnerPartId=-1|Location.X=708|Location.Y=331|Color=8388608|FontID=1|IsHidden=T|Text=3mm|Name=Length
|RECORD=41|OwnerIndex=433|IndexInSheet=12|OwnerPartId=-1|Location.X=708|Location.Y=331|Color=8388608|FontID=1|IsHidden=T|Text=TapeandReel|Name=Packaging
|RECORD=41|OwnerIndex=433|IndexInSheet=13|OwnerPartId=-1|Location.X=708|Location.Y=331|Color=8388608|FontID=1|IsHidden=T|Text=Jack|Name=Connector Type
|RECORD=41|OwnerIndex=433|IndexInSheet=14|OwnerPartId=-1|Location.X=708|Location.Y=331|Color=8388608|FontID=1|IsHidden=T|Text=LeadFree|Name=Lead Free
|RECORD=41|OwnerIndex=433|IndexInSheet=15|OwnerPartId=-1|Location.X=708|Location.Y=331|Color=8388608|FontID=1|IsHidden=T|Text=1|Name=Package Quantity
|RECORD=41|OwnerIndex=433|IndexInSheet=16|OwnerPartId=-1|Location.X=708|Location.Y=331|Color=8388608|FontID=1|IsHidden=T|Text=SMD/SMT|Name=Termination
|RECORD=41|OwnerIndex=433|IndexInSheet=17|OwnerPartId=-1|Location.X=708|Location.Y=331|Color=8388608|FontID=1|IsHidden=T|Text=CopperAlloy|Name=Contact Material
|RECORD=41|OwnerIndex=433|IndexInSheet=18|OwnerPartId=-1|Location.X=708|Location.Y=331|Color=8388608|FontID=1|IsHidden=T|Text=Pull|Name=Fastening Type
|RECORD=41|OwnerIndex=433|IndexInSheet=19|OwnerPartId=-1|Location.X=708|Location.Y=331|Color=8388608|FontID=1|IsHidden=T|Text=true|Name=RoHSCompliant
|RECORD=41|OwnerIndex=433|IndexInSheet=20|OwnerPartId=-1|Location.X=708|Location.Y=331|Color=8388608|FontID=1|IsHidden=T|Text=LiquidCrystalPolymer|Name=Body Material
|RECORD=41|OwnerIndex=433|IndexInSheet=21|OwnerPartId=-1|Location.X=708|Location.Y=331|Color=8388608|FontID=1|IsHidden=T|Text=SMD/SMT|Name=Case\/Package
|RECORD=41|OwnerIndex=433|IndexInSheet=22|OwnerPartId=-1|Location.X=708|Location.Y=331|Color=8388608|FontID=1|IsHidden=T|Text=90degC|Name=Max Operating Temperature
|RECORD=41|OwnerIndex=433|IndexInSheet=23|OwnerPartId=-1|Location.X=708|Location.Y=331|Color=8388608|FontID=1|IsHidden=T|Text=50Ohm|Name=Impedance
|RECORD=41|OwnerIndex=433|IndexInSheet=24|OwnerPartId=-1|Location.X=708|Location.Y=331|Color=8388608|FontID=2|IsHidden=T|Text=http://www.te.com/commerce/DocumentDelivery/DDEController?Action=srchrtrv&DocNm=1909763&DocType=Customer+Drawing&DocLang=English|Name=Datasheet URL
|RECORD=41|OwnerIndex=433|IndexInSheet=25|OwnerPartId=-1|Location.X=708|Location.Y=331|Color=8388608|FontID=1|IsHidden=T|Text=Gold|Name=Contact Plating
|RECORD=41|OwnerIndex=433|IndexInSheet=26|OwnerPartId=-1|Location.X=708|Location.Y=331|Color=8388608|FontID=1|IsHidden=T|Text=SurfaceMount|Name=Mounting Technology
|RECORD=41|OwnerIndex=433|IndexInSheet=27|OwnerPartId=-1|Location.X=708|Location.Y=331|Color=8388608|FontID=1|IsHidden=T|Text=6GHz|Name=Max Frequency
|RECORD=41|OwnerIndex=433|IndexInSheet=28|OwnerPartId=-1|Location.X=708|Location.Y=331|Color=8388608|FontID=1|IsHidden=T|Text=TECO-1909763-1|Name=Package Reference
|RECORD=41|OwnerIndex=433|IndexInSheet=29|OwnerPartId=-1|Location.X=708|Location.Y=331|Color=8388608|FontID=1|IsHidden=T|Text=Thermoplastic|Name=Insulation Material
|RECORD=41|OwnerIndex=433|IndexInSheet=30|OwnerPartId=-1|Location.X=708|Location.Y=331|Color=8388608|FontID=1|IsHidden=T|Text=-40degC|Name=Min Operating Temperature
|RECORD=41|OwnerIndex=433|IndexInSheet=31|OwnerPartId=-1|Location.X=708|Location.Y=331|Color=8388608|FontID=2|IsHidden=T|Text=http://www.te.com/|Name=Manufacturer URL
|RECORD=41|OwnerIndex=433|IndexInSheet=32|OwnerPartId=-1|Location.X=708|Location.Y=331|Color=8388608|FontID=1|IsHidden=T|Text=Gold|Name=Body Plating
|RECORD=41|OwnerIndex=433|IndexInSheet=33|OwnerPartId=-1|Location.X=708|Location.Y=331|Color=8388608|FontID=1|IsHidden=T|Text=Polymer|Name=Dielectric Material
|RECORD=41|OwnerIndex=433|IndexInSheet=34|OwnerPartId=-1|Location.X=708|Location.Y=331|Color=8388608|FontID=1|IsHidden=T|Text=TE Connectivity|Name=Manufacturer
|RECORD=41|OwnerIndex=433|IndexInSheet=35|OwnerPartId=-1|Location.X=708|Location.Y=331|Color=8388608|FontID=1|IsHidden=T|Text=Compliant|Name=ELV
|RECORD=41|OwnerIndex=433|IndexInSheet=36|OwnerPartId=-1|Location.X=708|Location.Y=331|Color=8388608|FontID=1|IsHidden=T|Text=Rev. B2, 11/2015|Name=Datasheet Version
|RECORD=41|OwnerIndex=433|IndexInSheet=37|OwnerPartId=-1|Location.X=708|Location.Y=331|Color=8388608|FontID=1|IsHidden=T|Text=No|Name=Radiation Hardening
|RECORD=41|OwnerIndex=433|IndexInSheet=38|OwnerPartId=-1|Location.X=708|Location.Y=331|Color=8388608|FontID=1|IsHidden=T|Text=3-Pin Surface Mount Device, Body 2.6 x 2.6 mm|Name=Package Description
|RECORD=41|OwnerIndex=433|IndexInSheet=39|OwnerPartId=-1|Location.X=708|Location.Y=331|Color=8388608|FontID=1|IsHidden=T|Text=Beige|Name=Housing Colour
|RECORD=34|OwnerIndex=433|IndexInSheet=-1|OwnerPartId=-1|Location.X=719|Location.Y=331|Color=8388608|FontID=1|Text=J5|Name=Designator|ReadOnlyState=1
|RECORD=41|OwnerIndex=433|IndexInSheet=-1|OwnerPartId=-1|Location.X=719|Location.Y=268|Color=8388608|FontID=1|Text=1909763-1|Name=Comment
|RECORD=44|OwnerIndex=433
|RECORD=45|OwnerIndex=479|IndexInSheet=-1|Description=SMD, 3-Leads, Body 2.6x2.6mm, Height 1.25mm|UseComponentLibrary=T|ModelName=TECO-1909763-1_V|ModelType=PCBLIB|DatafileCount=1|ModelDatafileEntity0=TECO-1909763-1_V|ModelDatafileKind0=PCBLib|IsCurrent=T|DatalinksLocked=T|DatabaseDatalinksLocked=T
|RECORD=46|OwnerIndex=480
|RECORD=48|OwnerIndex=480
|RECORD=41|OwnerIndex=482|IndexInSheet=-1|OwnerPartId=-1|Color=8388608|FontID=1|Text=2D|Name=Available Preview Images
|RECORD=1|LibReference=CN-S-4F-RF5|ComponentDescription=Coaxial connector, 50 Ohm, -65 to 165 degC, 5-Pin THD, RoHS, Bulk|PartCount=2|DisplayModeCount=1|IndexInSheet=57|OwnerPartId=-1|Location.X=720|Location.Y=240|CurrentPartId=1|LibraryPath=*|SourceLibraryName=Altium Content Vault|TargetFileName=*|AreaColor=11599871|Color=128|PartIDLocked=T|DesignItemId=CMP-2000-05705-1|AllPinCount=5
|RECORD=2|OwnerIndex=484|OwnerPartId=1|FormalType=1|Electrical=4|PinConglomerate=51|PinLength=10|Location.X=760|Location.Y=200|Name=5|Designator=5|SwapIDPart=Ž&Ž1|PinPropagationDelay=0.000000E+000
|RECORD=8|OwnerIndex=484|IsNotAccesible=T|IndexInSheet=1|OwnerPartId=1|Location.X=740|Location.Y=220|Radius=20|SecondaryRadius=20|LineWidth=1|Color=16711680|AreaColor=16777215
|RECORD=8|OwnerIndex=484|IsNotAccesible=T|IndexInSheet=2|OwnerPartId=1|Location.X=740|Location.Y=220|Radius=4|SecondaryRadius=4|LineWidth=1|Color=16711680|AreaColor=16777215
|RECORD=2|OwnerIndex=484|OwnerPartId=1|FormalType=1|Electrical=4|PinConglomerate=50|PinLength=10|Location.X=720|Location.Y=220|Name=1|Designator=1|PinPropagationDelay=0.000000E+000
|RECORD=2|OwnerIndex=484|OwnerPartId=1|FormalType=1|Electrical=4|PinConglomerate=51|PinLength=10|Location.X=730|Location.Y=200|Name=2|Designator=2|PinPropagationDelay=0.000000E+000
|RECORD=2|OwnerIndex=484|OwnerPartId=1|FormalType=1|Electrical=4|PinConglomerate=51|PinLength=10|Location.X=740|Location.Y=200|Name=3|Designator=3|PinPropagationDelay=0.000000E+000
|RECORD=2|OwnerIndex=484|OwnerPartId=1|FormalType=1|Electrical=4|PinConglomerate=51|PinLength=10|Location.X=750|Location.Y=200|Name=4|Designator=4|PinPropagationDelay=0.000000E+000
|RECORD=6|OwnerIndex=484|IsNotAccesible=T|IndexInSheet=7|OwnerPartId=1|LineWidth=1|Color=16711680|LocationCount=5|X1=720|Y1=200|X2=720|Y2=240|X3=760|Y3=240|X4=760|Y4=200|X5=720|Y5=200
|RECORD=6|OwnerIndex=484|IsNotAccesible=T|IndexInSheet=8|OwnerPartId=1|LineWidth=1|Color=16711680|LocationCount=2|X1=720|Y1=220|X2=736|Y2=220
|RECORD=41|OwnerIndex=484|IndexInSheet=9|OwnerPartId=-1|Location.X=708|Location.Y=241|Color=8388608|FontID=1|IsHidden=T|Text=ThroughHole|Name=Mounting Technology
|RECORD=41|OwnerIndex=484|IndexInSheet=10|OwnerPartId=-1|Location.X=708|Location.Y=241|Color=8388608|FontID=1|IsHidden=T|Text=ThroughHole,RightAngle|Name=Mounting Type
|RECORD=41|OwnerIndex=484|IndexInSheet=11|OwnerPartId=-1|Location.X=708|Location.Y=241|Color=8388608|FontID=1|IsHidden=T|Text=-|Name=Cable Group
|RECORD=41|OwnerIndex=484|IndexInSheet=12|OwnerPartId=-1|Location.X=708|Location.Y=241|Color=8388608|FontID=1|IsHidden=T|Text=901-143-6RFXMountingHole|Name=Catalog Drawings
|RECORD=41|OwnerIndex=484|IndexInSheet=13|OwnerPartId=-1|Location.X=708|Location.Y=241|Color=8388608|FontID=1|IsHidden=T|Text=901-143-6RFX.igs|Name=3D Model
|RECORD=41|OwnerIndex=484|IndexInSheet=14|OwnerPartId=-1|Location.X=708|Location.Y=241|Color=8388608|FontID=1|IsHidden=T|Text=-|Name=Series
|RECORD=41|OwnerIndex=484|IndexInSheet=15|OwnerPartId=-1|Location.X=708|Location.Y=241|Color=8388608|FontID=1|IsHidden=T|Text=5-Pin Through Hole Device, Body 7 x 7 mm, Pitch 2.54 mm|Name=Package Description
|RECORD=41|OwnerIndex=484|IndexInSheet=16|OwnerPartId=-1|Location.X=708|Location.Y=241|Color=8388608|FontID=1|IsHidden=T|Text=901-143-6RFX|Name=Package Reference
|RECORD=41|OwnerIndex=484|IndexInSheet=17|OwnerPartId=-1|Location.X=708|Location.Y=241|Color=8388608|FontID=1|IsHidden=T|Text=Brass|Name=Body Material
|RECORD=41|OwnerIndex=484|IndexInSheet=18|OwnerPartId=-1|Location.X=708|Location.Y=241|Color=8388608|FontID=1|IsHidden=T|Text=-|Name=Voltage Rating
|RECORD=41|OwnerIndex=484|IndexInSheet=19|OwnerPartId=-1|Location.X=708|Location.Y=241|Color=8388608|FontID=1|IsHidden=T|Text=1|Name=Standard Package
|RECORD=41|OwnerIndex=484|IndexInSheet=20|OwnerPartId=-1|Location.X=708|Location.Y=241|Color=8388608|FontID=1|IsHidden=T|Text=Jack,FemaleSocket|Name=Connector Type
|RECORD=41|OwnerIndex=484|IndexInSheet=21|OwnerPartId=-1|Location.X=708|Location.Y=241|Color=8388608|FontID=1|IsHidden=T|Text=Threaded|Name=Fastening Type
|RECORD=41|OwnerIndex=484|IndexInSheet=22|OwnerPartId=-1|Location.X=708|Location.Y=241|Color=8388608|FontID=1|IsHidden=T|Text=Gold|Name=Housing Color
|RECORD=41|OwnerIndex=484|IndexInSheet=23|OwnerPartId=-1|Location.X=708|Location.Y=241|Color=8388608|FontID=1|IsHidden=T|Text=Solder|Name=Shield Termination
|RECORD=41|OwnerIndex=484|IndexInSheet=24|OwnerPartId=-1|Location.X=708|Location.Y=241|Color=8388608|FontID=1|IsHidden=T|Text=901-143-6-RFX9011436RFXARFX1232|Name=Other Names
|RECORD=41|OwnerIndex=484|IndexInSheet=25|OwnerPartId=-1|Location.X=708|Location.Y=241|Color=8388608|FontID=2|IsHidden=T|Text=http://www.amphenolrf.com/downloads/dl/file/id/2712/product/3102/901_143_6rfx_customer_drawing.pdf|Name=Datasheet URL
|RECORD=41|OwnerIndex=484|IndexInSheet=26|OwnerPartId=-1|Location.X=708|Location.Y=241|Color=8388608|FontID=1|IsHidden=T|Text=CoaxialConnectors(RF)|Name=Family
|RECORD=41|OwnerIndex=484|IndexInSheet=27|OwnerPartId=-1|Location.X=708|Location.Y=241|Color=8388608|FontID=1|IsHidden=T|Text=SMA,RFX|Name=Online Catalog
|RECORD=41|OwnerIndex=484|IndexInSheet=28|OwnerPartId=-1|Location.X=708|Location.Y=241|Color=8388608|FontID=1|IsHidden=T|Text=18GHz|Name=Frequency - Max
|RECORD=41|OwnerIndex=484|IndexInSheet=29|OwnerPartId=-1|Location.X=708|Location.Y=241|Color=8388608|FontID=1|IsHidden=T|Text=Solder|Name=Contact Termination
|RECORD=41|OwnerIndex=484|IndexInSheet=30|OwnerPartId=-1|Location.X=708|Location.Y=241|Color=8388608|FontID=2|IsHidden=T|Text=http://www.amphenol.com/|Name=Manufacturer URL
|RECORD=41|OwnerIndex=484|IndexInSheet=31|OwnerPartId=-1|Location.X=708|Location.Y=241|Color=8388608|FontID=1|IsHidden=T|Text=Amphenol|Name=Manufacturer
|RECORD=41|OwnerIndex=484|IndexInSheet=32|OwnerPartId=-1|Location.X=708|Location.Y=241|Color=8388608|FontID=1|IsHidden=T|Text=-65°C~165°C|Name=Operating Temperature
|RECORD=41|OwnerIndex=484|IndexInSheet=33|OwnerPartId=-1|Location.X=708|Location.Y=241|Color=8388608|FontID=1|IsHidden=T|Text=Connectors,Interconnects|Name=Category
|RECORD=41|OwnerIndex=484|IndexInSheet=34|OwnerPartId=-1|Location.X=708|Location.Y=241|Color=8388608|FontID=1|IsHidden=T|Text=Bulk|Name=Packaging
|RECORD=41|OwnerIndex=484|IndexInSheet=35|OwnerPartId=-1|Location.X=708|Location.Y=241|Color=8388608|FontID=1|IsHidden=T|Text=Gold|Name=Body Finish
|RECORD=41|OwnerIndex=484|IndexInSheet=36|OwnerPartId=-1|Location.X=708|Location.Y=241|Color=8388608|FontID=1|IsHidden=T|Text=Polytetrafluoroethylene(PTFE)|Name=Dielectric Material
|RECORD=41|OwnerIndex=484|IndexInSheet=37|OwnerPartId=-1|Location.X=708|Location.Y=241|Color=8388608|FontID=1|IsHidden=T|Text=BerylliumCopper|Name=Center Contact Material
|RECORD=41|OwnerIndex=484|IndexInSheet=38|OwnerPartId=-1|Location.X=708|Location.Y=241|Color=8388608|FontID=1|IsHidden=T|Text=50Ohm|Name=Impedance
|RECORD=41|OwnerIndex=484|IndexInSheet=39|OwnerPartId=-1|Location.X=708|Location.Y=241|Color=8388608|FontID=1|IsHidden=T|Text=-|Name=Features
|RECORD=41|OwnerIndex=484|IndexInSheet=40|OwnerPartId=-1|Location.X=708|Location.Y=241|Color=8388608|FontID=1|IsHidden=T|Text=SMA|Name=Connector Style
|RECORD=41|OwnerIndex=484|IndexInSheet=41|OwnerPartId=-1|Location.X=708|Location.Y=241|Color=8388608|FontID=1|IsHidden=T|Text=Gold|Name=Center Contact Plating
|RECORD=41|OwnerIndex=484|IndexInSheet=42|OwnerPartId=-1|Location.X=708|Location.Y=241|Color=8388608|FontID=1|IsHidden=T|Text=Rev. C, 06/2010|Name=Datasheet Version
|RECORD=41|OwnerIndex=484|IndexInSheet=43|OwnerPartId=-1|Location.X=708|Location.Y=241|Color=8388608|FontID=1|IsHidden=T|Text=-|Name=Ingress Protection
|RECORD=34|OwnerIndex=484|IndexInSheet=-1|OwnerPartId=-1|Location.X=719|Location.Y=241|Color=8388608|FontID=1|Text=AN2|Name=Designator|ReadOnlyState=1
|RECORD=41|OwnerIndex=484|IndexInSheet=-1|OwnerPartId=-1|Location.X=719|Location.Y=178|Color=8388608|FontID=1|Text=901-143-6RFX|Name=Comment
|RECORD=44|OwnerIndex=484
|RECORD=45|OwnerIndex=536|IndexInSheet=-1|Description=THD, 5-Leads, Body 7x7mm, Pitch 2.54mm|UseComponentLibrary=T|ModelName=AMPH-901-143-6RFX_V|ModelType=PCBLIB|DatafileCount=1|ModelDatafileEntity0=AMPH-901-143-6RFX_V|ModelDatafileKind0=PCBLib|IsCurrent=T|DatalinksLocked=T|DatabaseDatalinksLocked=T
|RECORD=46|OwnerIndex=537
|RECORD=48|OwnerIndex=537
|RECORD=41|OwnerIndex=539|IndexInSheet=-1|OwnerPartId=-1|Color=8388608|FontID=1|Text=2D|Name=Available Preview Images
|RECORD=1|LibReference=CN-1P-M-RF3|ComponentDescription=Ultra Miniature Coaxial Connector Jack, 60 V, 50 Ohm, -40 to 90 degC, RoHS, Tape and Reel|PartCount=2|DisplayModeCount=1|IndexInSheet=58|OwnerPartId=-1|Location.X=1310|Location.Y=360|CurrentPartId=1|LibraryPath=*|SourceLibraryName=Altium Content Vault|TargetFileName=*|AreaColor=11599871|Color=128|PartIDLocked=T|DesignItemId=CMP-2000-07505-1|AllPinCount=3
|RECORD=8|OwnerIndex=541|IsNotAccesible=T|OwnerPartId=1|Location.X=1330|Location.Y=340|Radius=20|SecondaryRadius=20|LineWidth=1|Color=16711680|AreaColor=16777215
|RECORD=8|OwnerIndex=541|IsNotAccesible=T|IndexInSheet=1|OwnerPartId=1|Location.X=1330|Location.Y=340|Radius=4|SecondaryRadius=4|LineWidth=1|Color=16711680|AreaColor=16777215
|RECORD=2|OwnerIndex=541|OwnerPartId=1|FormalType=1|Electrical=4|PinConglomerate=51|PinLength=10|Location.X=1320|Location.Y=320|Name=1|Designator=1|PinPropagationDelay=0.000000E+000
|RECORD=2|OwnerIndex=541|OwnerPartId=1|FormalType=1|Electrical=4|PinConglomerate=50|PinLength=10|Location.X=1310|Location.Y=340|Name=2|Designator=2|PinPropagationDelay=0.000000E+000
|RECORD=2|OwnerIndex=541|OwnerPartId=1|FormalType=1|Electrical=4|PinConglomerate=51|PinLength=10|Location.X=1340|Location.Y=320|Name=3|Designator=3|PinPropagationDelay=0.000000E+000
|RECORD=6|OwnerIndex=541|IsNotAccesible=T|IndexInSheet=5|OwnerPartId=1|LineWidth=1|Color=16711680|LocationCount=5|X1=1310|Y1=320|X2=1310|Y2=360|X3=1350|Y3=360|X4=1350|Y4=320|X5=1310|Y5=320
|RECORD=6|OwnerIndex=541|IsNotAccesible=T|IndexInSheet=6|OwnerPartId=1|LineWidth=1|Color=16711680|LocationCount=2|X1=1310|Y1=340|X2=1326|Y2=340
|RECORD=41|OwnerIndex=541|IndexInSheet=7|OwnerPartId=-1|Location.X=1298|Location.Y=361|Color=8388608|FontID=1|IsHidden=T|Text=Straight|Name=Orientation
|RECORD=41|OwnerIndex=541|IndexInSheet=8|OwnerPartId=-1|Location.X=1298|Location.Y=361|Color=8388608|FontID=1|IsHidden=T|Text=Female|Name=Gender
|RECORD=41|OwnerIndex=541|IndexInSheet=9|OwnerPartId=-1|Location.X=1298|Location.Y=361|Color=8388608|FontID=1|IsHidden=T|Text=Vertical|Name=PCB Mounting Orientation
|RECORD=41|OwnerIndex=541|IndexInSheet=10|OwnerPartId=-1|Location.X=1298|Location.Y=361|Color=8388608|FontID=1|IsHidden=T|Text=SurfaceMount|Name=Mount
|RECORD=41|OwnerIndex=541|IndexInSheet=11|OwnerPartId=-1|Location.X=1298|Location.Y=361|Color=8388608|FontID=1|IsHidden=T|Text=3mm|Name=Length
|RECORD=41|OwnerIndex=541|IndexInSheet=12|OwnerPartId=-1|Location.X=1298|Location.Y=361|Color=8388608|FontID=1|IsHidden=T|Text=TapeandReel|Name=Packaging
|RECORD=41|OwnerIndex=541|IndexInSheet=13|OwnerPartId=-1|Location.X=1298|Location.Y=361|Color=8388608|FontID=1|IsHidden=T|Text=Jack|Name=Connector Type
|RECORD=41|OwnerIndex=541|IndexInSheet=14|OwnerPartId=-1|Location.X=1298|Location.Y=361|Color=8388608|FontID=1|IsHidden=T|Text=LeadFree|Name=Lead Free
|RECORD=41|OwnerIndex=541|IndexInSheet=15|OwnerPartId=-1|Location.X=1298|Location.Y=361|Color=8388608|FontID=1|IsHidden=T|Text=1|Name=Package Quantity
|RECORD=41|OwnerIndex=541|IndexInSheet=16|OwnerPartId=-1|Location.X=1298|Location.Y=361|Color=8388608|FontID=1|IsHidden=T|Text=SMD/SMT|Name=Termination
|RECORD=41|OwnerIndex=541|IndexInSheet=17|OwnerPartId=-1|Location.X=1298|Location.Y=361|Color=8388608|FontID=1|IsHidden=T|Text=CopperAlloy|Name=Contact Material
|RECORD=41|OwnerIndex=541|IndexInSheet=18|OwnerPartId=-1|Location.X=1298|Location.Y=361|Color=8388608|FontID=1|IsHidden=T|Text=Pull|Name=Fastening Type
|RECORD=41|OwnerIndex=541|IndexInSheet=19|OwnerPartId=-1|Location.X=1298|Location.Y=361|Color=8388608|FontID=1|IsHidden=T|Text=true|Name=RoHSCompliant
|RECORD=41|OwnerIndex=541|IndexInSheet=20|OwnerPartId=-1|Location.X=1298|Location.Y=361|Color=8388608|FontID=1|IsHidden=T|Text=LiquidCrystalPolymer|Name=Body Material
|RECORD=41|OwnerIndex=541|IndexInSheet=21|OwnerPartId=-1|Location.X=1298|Location.Y=361|Color=8388608|FontID=1|IsHidden=T|Text=SMD/SMT|Name=Case\/Package
|RECORD=41|OwnerIndex=541|IndexInSheet=22|OwnerPartId=-1|Location.X=1298|Location.Y=361|Color=8388608|FontID=1|IsHidden=T|Text=90degC|Name=Max Operating Temperature
|RECORD=41|OwnerIndex=541|IndexInSheet=23|OwnerPartId=-1|Location.X=1298|Location.Y=361|Color=8388608|FontID=1|IsHidden=T|Text=50Ohm|Name=Impedance
|RECORD=41|OwnerIndex=541|IndexInSheet=24|OwnerPartId=-1|Location.X=1298|Location.Y=361|Color=8388608|FontID=2|IsHidden=T|Text=http://www.te.com/commerce/DocumentDelivery/DDEController?Action=srchrtrv&DocNm=1909763&DocType=Customer+Drawing&DocLang=English|Name=Datasheet URL
|RECORD=41|OwnerIndex=541|IndexInSheet=25|OwnerPartId=-1|Location.X=1298|Location.Y=361|Color=8388608|FontID=1|IsHidden=T|Text=Gold|Name=Contact Plating
|RECORD=41|OwnerIndex=541|IndexInSheet=26|OwnerPartId=-1|Location.X=1298|Location.Y=361|Color=8388608|FontID=1|IsHidden=T|Text=SurfaceMount|Name=Mounting Technology
|RECORD=41|OwnerIndex=541|IndexInSheet=27|OwnerPartId=-1|Location.X=1298|Location.Y=361|Color=8388608|FontID=1|IsHidden=T|Text=6GHz|Name=Max Frequency
|RECORD=41|OwnerIndex=541|IndexInSheet=28|OwnerPartId=-1|Location.X=1298|Location.Y=361|Color=8388608|FontID=1|IsHidden=T|Text=TECO-1909763-1|Name=Package Reference
|RECORD=41|OwnerIndex=541|IndexInSheet=29|OwnerPartId=-1|Location.X=1298|Location.Y=361|Color=8388608|FontID=1|IsHidden=T|Text=Thermoplastic|Name=Insulation Material
|RECORD=41|OwnerIndex=541|IndexInSheet=30|OwnerPartId=-1|Location.X=1298|Location.Y=361|Color=8388608|FontID=1|IsHidden=T|Text=-40degC|Name=Min Operating Temperature
|RECORD=41|OwnerIndex=541|IndexInSheet=31|OwnerPartId=-1|Location.X=1298|Location.Y=361|Color=8388608|FontID=2|IsHidden=T|Text=http://www.te.com/|Name=Manufacturer URL
|RECORD=41|OwnerIndex=541|IndexInSheet=32|OwnerPartId=-1|Location.X=1298|Location.Y=361|Color=8388608|FontID=1|IsHidden=T|Text=Gold|Name=Body Plating
|RECORD=41|OwnerIndex=541|IndexInSheet=33|OwnerPartId=-1|Location.X=1298|Location.Y=361|Color=8388608|FontID=1|IsHidden=T|Text=Polymer|Name=Dielectric Material
|RECORD=41|OwnerIndex=541|IndexInSheet=34|OwnerPartId=-1|Location.X=1298|Location.Y=361|Color=8388608|FontID=1|IsHidden=T|Text=TE Connectivity|Name=Manufacturer
|RECORD=41|OwnerIndex=541|IndexInSheet=35|OwnerPartId=-1|Location.X=1298|Location.Y=361|Color=8388608|FontID=1|IsHidden=T|Text=Compliant|Name=ELV
|RECORD=41|OwnerIndex=541|IndexInSheet=36|OwnerPartId=-1|Location.X=1298|Location.Y=361|Color=8388608|FontID=1|IsHidden=T|Text=Rev. B2, 11/2015|Name=Datasheet Version
|RECORD=41|OwnerIndex=541|IndexInSheet=37|OwnerPartId=-1|Location.X=1298|Location.Y=361|Color=8388608|FontID=1|IsHidden=T|Text=No|Name=Radiation Hardening
|RECORD=41|OwnerIndex=541|IndexInSheet=38|OwnerPartId=-1|Location.X=1298|Location.Y=361|Color=8388608|FontID=1|IsHidden=T|Text=3-Pin Surface Mount Device, Body 2.6 x 2.6 mm|Name=Package Description
|RECORD=41|OwnerIndex=541|IndexInSheet=39|OwnerPartId=-1|Location.X=1298|Location.Y=361|Color=8388608|FontID=1|IsHidden=T|Text=Beige|Name=Housing Colour
|RECORD=34|OwnerIndex=541|IndexInSheet=-1|OwnerPartId=-1|Location.X=1309|Location.Y=361|Color=8388608|FontID=1|Text=J10|Name=Designator|ReadOnlyState=1
|RECORD=41|OwnerIndex=541|IndexInSheet=-1|OwnerPartId=-1|Location.X=1309|Location.Y=298|Color=8388608|FontID=1|Text=1909763-1|Name=Comment
|RECORD=44|OwnerIndex=541
|RECORD=45|OwnerIndex=587|IndexInSheet=-1|Description=SMD, 3-Leads, Body 2.6x2.6mm, Height 1.25mm|UseComponentLibrary=T|ModelName=TECO-1909763-1_V|ModelType=PCBLIB|DatafileCount=1|ModelDatafileEntity0=TECO-1909763-1_V|ModelDatafileKind0=PCBLib|IsCurrent=T|DatalinksLocked=T|DatabaseDatalinksLocked=T
|RECORD=46|OwnerIndex=588
|RECORD=48|OwnerIndex=588
|RECORD=41|OwnerIndex=590|IndexInSheet=-1|OwnerPartId=-1|Color=8388608|FontID=1|Text=2D|Name=Available Preview Images
|RECORD=1|LibReference=CN-S-4F-RF5|ComponentDescription=Coaxial connector, 50 Ohm, -65 to 165 degC, 5-Pin THD, RoHS, Bulk|PartCount=2|DisplayModeCount=1|IndexInSheet=59|OwnerPartId=-1|Location.X=1310|Location.Y=270|CurrentPartId=1|LibraryPath=*|SourceLibraryName=Altium Content Vault|TargetFileName=*|AreaColor=11599871|Color=128|PartIDLocked=T|DesignItemId=CMP-2000-05705-1|AllPinCount=5
|RECORD=2|OwnerIndex=592|OwnerPartId=1|FormalType=1|Electrical=4|PinConglomerate=51|PinLength=10|Location.X=1350|Location.Y=230|Name=5|Designator=5|SwapIDPart=Ž&Ž1|PinPropagationDelay=0.000000E+000
|RECORD=8|OwnerIndex=592|IsNotAccesible=T|IndexInSheet=1|OwnerPartId=1|Location.X=1330|Location.Y=250|Radius=20|SecondaryRadius=20|LineWidth=1|Color=16711680|AreaColor=16777215
|RECORD=8|OwnerIndex=592|IsNotAccesible=T|IndexInSheet=2|OwnerPartId=1|Location.X=1330|Location.Y=250|Radius=4|SecondaryRadius=4|LineWidth=1|Color=16711680|AreaColor=16777215
|RECORD=2|OwnerIndex=592|OwnerPartId=1|FormalType=1|Electrical=4|PinConglomerate=50|PinLength=10|Location.X=1310|Location.Y=250|Name=1|Designator=1|PinPropagationDelay=0.000000E+000
|RECORD=2|OwnerIndex=592|OwnerPartId=1|FormalType=1|Electrical=4|PinConglomerate=51|PinLength=10|Location.X=1320|Location.Y=230|Name=2|Designator=2|PinPropagationDelay=0.000000E+000
|RECORD=2|OwnerIndex=592|OwnerPartId=1|FormalType=1|Electrical=4|PinConglomerate=51|PinLength=10|Location.X=1330|Location.Y=230|Name=3|Designator=3|PinPropagationDelay=0.000000E+000
|RECORD=2|OwnerIndex=592|OwnerPartId=1|FormalType=1|Electrical=4|PinConglomerate=51|PinLength=10|Location.X=1340|Location.Y=230|Name=4|Designator=4|PinPropagationDelay=0.000000E+000
|RECORD=6|OwnerIndex=592|IsNotAccesible=T|IndexInSheet=7|OwnerPartId=1|LineWidth=1|Color=16711680|LocationCount=5|X1=1310|Y1=230|X2=1310|Y2=270|X3=1350|Y3=270|X4=1350|Y4=230|X5=1310|Y5=230
|RECORD=6|OwnerIndex=592|IsNotAccesible=T|IndexInSheet=8|OwnerPartId=1|LineWidth=1|Color=16711680|LocationCount=2|X1=1310|Y1=250|X2=1326|Y2=250
|RECORD=41|OwnerIndex=592|IndexInSheet=9|OwnerPartId=-1|Location.X=1298|Location.Y=271|Color=8388608|FontID=1|IsHidden=T|Text=ThroughHole|Name=Mounting Technology
|RECORD=41|OwnerIndex=592|IndexInSheet=10|OwnerPartId=-1|Location.X=1298|Location.Y=271|Color=8388608|FontID=1|IsHidden=T|Text=ThroughHole,RightAngle|Name=Mounting Type
|RECORD=41|OwnerIndex=592|IndexInSheet=11|OwnerPartId=-1|Location.X=1298|Location.Y=271|Color=8388608|FontID=1|IsHidden=T|Text=-|Name=Cable Group
|RECORD=41|OwnerIndex=592|IndexInSheet=12|OwnerPartId=-1|Location.X=1298|Location.Y=271|Color=8388608|FontID=1|IsHidden=T|Text=901-143-6RFXMountingHole|Name=Catalog Drawings
|RECORD=41|OwnerIndex=592|IndexInSheet=13|OwnerPartId=-1|Location.X=1298|Location.Y=271|Color=8388608|FontID=1|IsHidden=T|Text=901-143-6RFX.igs|Name=3D Model
|RECORD=41|OwnerIndex=592|IndexInSheet=14|OwnerPartId=-1|Location.X=1298|Location.Y=271|Color=8388608|FontID=1|IsHidden=T|Text=-|Name=Series
|RECORD=41|OwnerIndex=592|IndexInSheet=15|OwnerPartId=-1|Location.X=1298|Location.Y=271|Color=8388608|FontID=1|IsHidden=T|Text=5-Pin Through Hole Device, Body 7 x 7 mm, Pitch 2.54 mm|Name=Package Description
|RECORD=41|OwnerIndex=592|IndexInSheet=16|OwnerPartId=-1|Location.X=1298|Location.Y=271|Color=8388608|FontID=1|IsHidden=T|Text=901-143-6RFX|Name=Package Reference
|RECORD=41|OwnerIndex=592|IndexInSheet=17|OwnerPartId=-1|Location.X=1298|Location.Y=271|Color=8388608|FontID=1|IsHidden=T|Text=Brass|Name=Body Material
|RECORD=41|OwnerIndex=592|IndexInSheet=18|OwnerPartId=-1|Location.X=1298|Location.Y=271|Color=8388608|FontID=1|IsHidden=T|Text=-|Name=Voltage Rating
|RECORD=41|OwnerIndex=592|IndexInSheet=19|OwnerPartId=-1|Location.X=1298|Location.Y=271|Color=8388608|FontID=1|IsHidden=T|Text=1|Name=Standard Package
|RECORD=41|OwnerIndex=592|IndexInSheet=20|OwnerPartId=-1|Location.X=1298|Location.Y=271|Color=8388608|FontID=1|IsHidden=T|Text=Jack,FemaleSocket|Name=Connector Type
|RECORD=41|OwnerIndex=592|IndexInSheet=21|OwnerPartId=-1|Location.X=1298|Location.Y=271|Color=8388608|FontID=1|IsHidden=T|Text=Threaded|Name=Fastening Type
|RECORD=41|OwnerIndex=592|IndexInSheet=22|OwnerPartId=-1|Location.X=1298|Location.Y=271|Color=8388608|FontID=1|IsHidden=T|Text=Gold|Name=Housing Color
|RECORD=41|OwnerIndex=592|IndexInSheet=23|OwnerPartId=-1|Location.X=1298|Location.Y=271|Color=8388608|FontID=1|IsHidden=T|Text=Solder|Name=Shield Termination
|RECORD=41|OwnerIndex=592|IndexInSheet=24|OwnerPartId=-1|Location.X=1298|Location.Y=271|Color=8388608|FontID=1|IsHidden=T|Text=901-143-6-RFX9011436RFXARFX1232|Name=Other Names
|RECORD=41|OwnerIndex=592|IndexInSheet=25|OwnerPartId=-1|Location.X=1298|Location.Y=271|Color=8388608|FontID=2|IsHidden=T|Text=http://www.amphenolrf.com/downloads/dl/file/id/2712/product/3102/901_143_6rfx_customer_drawing.pdf|Name=Datasheet URL
|RECORD=41|OwnerIndex=592|IndexInSheet=26|OwnerPartId=-1|Location.X=1298|Location.Y=271|Color=8388608|FontID=1|IsHidden=T|Text=CoaxialConnectors(RF)|Name=Family
|RECORD=41|OwnerIndex=592|IndexInSheet=27|OwnerPartId=-1|Location.X=1298|Location.Y=271|Color=8388608|FontID=1|IsHidden=T|Text=SMA,RFX|Name=Online Catalog
|RECORD=41|OwnerIndex=592|IndexInSheet=28|OwnerPartId=-1|Location.X=1298|Location.Y=271|Color=8388608|FontID=1|IsHidden=T|Text=18GHz|Name=Frequency - Max
|RECORD=41|OwnerIndex=592|IndexInSheet=29|OwnerPartId=-1|Location.X=1298|Location.Y=271|Color=8388608|FontID=1|IsHidden=T|Text=Solder|Name=Contact Termination
|RECORD=41|OwnerIndex=592|IndexInSheet=30|OwnerPartId=-1|Location.X=1298|Location.Y=271|Color=8388608|FontID=2|IsHidden=T|Text=http://www.amphenol.com/|Name=Manufacturer URL
|RECORD=41|OwnerIndex=592|IndexInSheet=31|OwnerPartId=-1|Location.X=1298|Location.Y=271|Color=8388608|FontID=1|IsHidden=T|Text=Amphenol|Name=Manufacturer
|RECORD=41|OwnerIndex=592|IndexInSheet=32|OwnerPartId=-1|Location.X=1298|Location.Y=271|Color=8388608|FontID=1|IsHidden=T|Text=-65°C~165°C|Name=Operating Temperature
|RECORD=41|OwnerIndex=592|IndexInSheet=33|OwnerPartId=-1|Location.X=1298|Location.Y=271|Color=8388608|FontID=1|IsHidden=T|Text=Connectors,Interconnects|Name=Category
|RECORD=41|OwnerIndex=592|IndexInSheet=34|OwnerPartId=-1|Location.X=1298|Location.Y=271|Color=8388608|FontID=1|IsHidden=T|Text=Bulk|Name=Packaging
|RECORD=41|OwnerIndex=592|IndexInSheet=35|OwnerPartId=-1|Location.X=1298|Location.Y=271|Color=8388608|FontID=1|IsHidden=T|Text=Gold|Name=Body Finish
|RECORD=41|OwnerIndex=592|IndexInSheet=36|OwnerPartId=-1|Location.X=1298|Location.Y=271|Color=8388608|FontID=1|IsHidden=T|Text=Polytetrafluoroethylene(PTFE)|Name=Dielectric Material
|RECORD=41|OwnerIndex=592|IndexInSheet=37|OwnerPartId=-1|Location.X=1298|Location.Y=271|Color=8388608|FontID=1|IsHidden=T|Text=BerylliumCopper|Name=Center Contact Material
|RECORD=41|OwnerIndex=592|IndexInSheet=38|OwnerPartId=-1|Location.X=1298|Location.Y=271|Color=8388608|FontID=1|IsHidden=T|Text=50Ohm|Name=Impedance
|RECORD=41|OwnerIndex=592|IndexInSheet=39|OwnerPartId=-1|Location.X=1298|Location.Y=271|Color=8388608|FontID=1|IsHidden=T|Text=-|Name=Features
|RECORD=41|OwnerIndex=592|IndexInSheet=40|OwnerPartId=-1|Location.X=1298|Location.Y=271|Color=8388608|FontID=1|IsHidden=T|Text=SMA|Name=Connector Style
|RECORD=41|OwnerIndex=592|IndexInSheet=41|OwnerPartId=-1|Location.X=1298|Location.Y=271|Color=8388608|FontID=1|IsHidden=T|Text=Gold|Name=Center Contact Plating
|RECORD=41|OwnerIndex=592|IndexInSheet=42|OwnerPartId=-1|Location.X=1298|Location.Y=271|Color=8388608|FontID=1|IsHidden=T|Text=Rev. C, 06/2010|Name=Datasheet Version
|RECORD=41|OwnerIndex=592|IndexInSheet=43|OwnerPartId=-1|Location.X=1298|Location.Y=271|Color=8388608|FontID=1|IsHidden=T|Text=-|Name=Ingress Protection
|RECORD=34|OwnerIndex=592|IndexInSheet=-1|OwnerPartId=-1|Location.X=1309|Location.Y=271|Color=8388608|FontID=1|Text=AN4|Name=Designator|ReadOnlyState=1
|RECORD=41|OwnerIndex=592|IndexInSheet=-1|OwnerPartId=-1|Location.X=1309|Location.Y=208|Color=8388608|FontID=1|Text=901-143-6RFX|Name=Comment
|RECORD=44|OwnerIndex=592
|RECORD=45|OwnerIndex=644|IndexInSheet=-1|Description=THD, 5-Leads, Body 7x7mm, Pitch 2.54mm|UseComponentLibrary=T|ModelName=AMPH-901-143-6RFX_V|ModelType=PCBLIB|DatafileCount=1|ModelDatafileEntity0=AMPH-901-143-6RFX_V|ModelDatafileKind0=PCBLib|IsCurrent=T|DatalinksLocked=T|DatabaseDatalinksLocked=T
|RECORD=46|OwnerIndex=645
|RECORD=48|OwnerIndex=645
|RECORD=41|OwnerIndex=647|IndexInSheet=-1|OwnerPartId=-1|Color=8388608|FontID=1|Text=2D|Name=Available Preview Images
|RECORD=1|LibReference=CN-1P-M-RF3|ComponentDescription=Ultra Miniature Coaxial Connector Jack, 60 V, 50 Ohm, -40 to 90 degC, RoHS, Tape and Reel|PartCount=2|DisplayModeCount=1|IndexInSheet=60|OwnerPartId=-1|Location.X=1310|Location.Y=680|CurrentPartId=1|LibraryPath=*|SourceLibraryName=Altium Content Vault|TargetFileName=*|AreaColor=11599871|Color=128|PartIDLocked=T|DesignItemId=CMP-2000-07505-1|AllPinCount=3
|RECORD=8|OwnerIndex=649|IsNotAccesible=T|OwnerPartId=1|Location.X=1330|Location.Y=660|Radius=20|SecondaryRadius=20|LineWidth=1|Color=16711680|AreaColor=16777215
|RECORD=8|OwnerIndex=649|IsNotAccesible=T|IndexInSheet=1|OwnerPartId=1|Location.X=1330|Location.Y=660|Radius=4|SecondaryRadius=4|LineWidth=1|Color=16711680|AreaColor=16777215
|RECORD=2|OwnerIndex=649|OwnerPartId=1|FormalType=1|Electrical=4|PinConglomerate=51|PinLength=10|Location.X=1320|Location.Y=640|Name=1|Designator=1|PinPropagationDelay=0.000000E+000
|RECORD=2|OwnerIndex=649|OwnerPartId=1|FormalType=1|Electrical=4|PinConglomerate=50|PinLength=10|Location.X=1310|Location.Y=660|Name=2|Designator=2|PinPropagationDelay=0.000000E+000
|RECORD=2|OwnerIndex=649|OwnerPartId=1|FormalType=1|Electrical=4|PinConglomerate=51|PinLength=10|Location.X=1340|Location.Y=640|Name=3|Designator=3|PinPropagationDelay=0.000000E+000
|RECORD=6|OwnerIndex=649|IsNotAccesible=T|IndexInSheet=5|OwnerPartId=1|LineWidth=1|Color=16711680|LocationCount=5|X1=1310|Y1=640|X2=1310|Y2=680|X3=1350|Y3=680|X4=1350|Y4=640|X5=1310|Y5=640
|RECORD=6|OwnerIndex=649|IsNotAccesible=T|IndexInSheet=6|OwnerPartId=1|LineWidth=1|Color=16711680|LocationCount=2|X1=1310|Y1=660|X2=1326|Y2=660
|RECORD=41|OwnerIndex=649|IndexInSheet=7|OwnerPartId=-1|Location.X=1298|Location.Y=681|Color=8388608|FontID=1|IsHidden=T|Text=Straight|Name=Orientation
|RECORD=41|OwnerIndex=649|IndexInSheet=8|OwnerPartId=-1|Location.X=1298|Location.Y=681|Color=8388608|FontID=1|IsHidden=T|Text=Female|Name=Gender
|RECORD=41|OwnerIndex=649|IndexInSheet=9|OwnerPartId=-1|Location.X=1298|Location.Y=681|Color=8388608|FontID=1|IsHidden=T|Text=Vertical|Name=PCB Mounting Orientation
|RECORD=41|OwnerIndex=649|IndexInSheet=10|OwnerPartId=-1|Location.X=1298|Location.Y=681|Color=8388608|FontID=1|IsHidden=T|Text=SurfaceMount|Name=Mount
|RECORD=41|OwnerIndex=649|IndexInSheet=11|OwnerPartId=-1|Location.X=1298|Location.Y=681|Color=8388608|FontID=1|IsHidden=T|Text=3mm|Name=Length
|RECORD=41|OwnerIndex=649|IndexInSheet=12|OwnerPartId=-1|Location.X=1298|Location.Y=681|Color=8388608|FontID=1|IsHidden=T|Text=TapeandReel|Name=Packaging
|RECORD=41|OwnerIndex=649|IndexInSheet=13|OwnerPartId=-1|Location.X=1298|Location.Y=681|Color=8388608|FontID=1|IsHidden=T|Text=Jack|Name=Connector Type
|RECORD=41|OwnerIndex=649|IndexInSheet=14|OwnerPartId=-1|Location.X=1298|Location.Y=681|Color=8388608|FontID=1|IsHidden=T|Text=LeadFree|Name=Lead Free
|RECORD=41|OwnerIndex=649|IndexInSheet=15|OwnerPartId=-1|Location.X=1298|Location.Y=681|Color=8388608|FontID=1|IsHidden=T|Text=1|Name=Package Quantity
|RECORD=41|OwnerIndex=649|IndexInSheet=16|OwnerPartId=-1|Location.X=1298|Location.Y=681|Color=8388608|FontID=1|IsHidden=T|Text=SMD/SMT|Name=Termination
|RECORD=41|OwnerIndex=649|IndexInSheet=17|OwnerPartId=-1|Location.X=1298|Location.Y=681|Color=8388608|FontID=1|IsHidden=T|Text=CopperAlloy|Name=Contact Material
|RECORD=41|OwnerIndex=649|IndexInSheet=18|OwnerPartId=-1|Location.X=1298|Location.Y=681|Color=8388608|FontID=1|IsHidden=T|Text=Pull|Name=Fastening Type
|RECORD=41|OwnerIndex=649|IndexInSheet=19|OwnerPartId=-1|Location.X=1298|Location.Y=681|Color=8388608|FontID=1|IsHidden=T|Text=true|Name=RoHSCompliant
|RECORD=41|OwnerIndex=649|IndexInSheet=20|OwnerPartId=-1|Location.X=1298|Location.Y=681|Color=8388608|FontID=1|IsHidden=T|Text=LiquidCrystalPolymer|Name=Body Material
|RECORD=41|OwnerIndex=649|IndexInSheet=21|OwnerPartId=-1|Location.X=1298|Location.Y=681|Color=8388608|FontID=1|IsHidden=T|Text=SMD/SMT|Name=Case\/Package
|RECORD=41|OwnerIndex=649|IndexInSheet=22|OwnerPartId=-1|Location.X=1298|Location.Y=681|Color=8388608|FontID=1|IsHidden=T|Text=90degC|Name=Max Operating Temperature
|RECORD=41|OwnerIndex=649|IndexInSheet=23|OwnerPartId=-1|Location.X=1298|Location.Y=681|Color=8388608|FontID=1|IsHidden=T|Text=50Ohm|Name=Impedance
|RECORD=41|OwnerIndex=649|IndexInSheet=24|OwnerPartId=-1|Location.X=1298|Location.Y=681|Color=8388608|FontID=2|IsHidden=T|Text=http://www.te.com/commerce/DocumentDelivery/DDEController?Action=srchrtrv&DocNm=1909763&DocType=Customer+Drawing&DocLang=English|Name=Datasheet URL
|RECORD=41|OwnerIndex=649|IndexInSheet=25|OwnerPartId=-1|Location.X=1298|Location.Y=681|Color=8388608|FontID=1|IsHidden=T|Text=Gold|Name=Contact Plating
|RECORD=41|OwnerIndex=649|IndexInSheet=26|OwnerPartId=-1|Location.X=1298|Location.Y=681|Color=8388608|FontID=1|IsHidden=T|Text=SurfaceMount|Name=Mounting Technology
|RECORD=41|OwnerIndex=649|IndexInSheet=27|OwnerPartId=-1|Location.X=1298|Location.Y=681|Color=8388608|FontID=1|IsHidden=T|Text=6GHz|Name=Max Frequency
|RECORD=41|OwnerIndex=649|IndexInSheet=28|OwnerPartId=-1|Location.X=1298|Location.Y=681|Color=8388608|FontID=1|IsHidden=T|Text=TECO-1909763-1|Name=Package Reference
|RECORD=41|OwnerIndex=649|IndexInSheet=29|OwnerPartId=-1|Location.X=1298|Location.Y=681|Color=8388608|FontID=1|IsHidden=T|Text=Thermoplastic|Name=Insulation Material
|RECORD=41|OwnerIndex=649|IndexInSheet=30|OwnerPartId=-1|Location.X=1298|Location.Y=681|Color=8388608|FontID=1|IsHidden=T|Text=-40degC|Name=Min Operating Temperature
|RECORD=41|OwnerIndex=649|IndexInSheet=31|OwnerPartId=-1|Location.X=1298|Location.Y=681|Color=8388608|FontID=2|IsHidden=T|Text=http://www.te.com/|Name=Manufacturer URL
|RECORD=41|OwnerIndex=649|IndexInSheet=32|OwnerPartId=-1|Location.X=1298|Location.Y=681|Color=8388608|FontID=1|IsHidden=T|Text=Gold|Name=Body Plating
|RECORD=41|OwnerIndex=649|IndexInSheet=33|OwnerPartId=-1|Location.X=1298|Location.Y=681|Color=8388608|FontID=1|IsHidden=T|Text=Polymer|Name=Dielectric Material
|RECORD=41|OwnerIndex=649|IndexInSheet=34|OwnerPartId=-1|Location.X=1298|Location.Y=681|Color=8388608|FontID=1|IsHidden=T|Text=TE Connectivity|Name=Manufacturer
|RECORD=41|OwnerIndex=649|IndexInSheet=35|OwnerPartId=-1|Location.X=1298|Location.Y=681|Color=8388608|FontID=1|IsHidden=T|Text=Compliant|Name=ELV
|RECORD=41|OwnerIndex=649|IndexInSheet=36|OwnerPartId=-1|Location.X=1298|Location.Y=681|Color=8388608|FontID=1|IsHidden=T|Text=Rev. B2, 11/2015|Name=Datasheet Version
|RECORD=41|OwnerIndex=649|IndexInSheet=37|OwnerPartId=-1|Location.X=1298|Location.Y=681|Color=8388608|FontID=1|IsHidden=T|Text=No|Name=Radiation Hardening
|RECORD=41|OwnerIndex=649|IndexInSheet=38|OwnerPartId=-1|Location.X=1298|Location.Y=681|Color=8388608|FontID=1|IsHidden=T|Text=3-Pin Surface Mount Device, Body 2.6 x 2.6 mm|Name=Package Description
|RECORD=41|OwnerIndex=649|IndexInSheet=39|OwnerPartId=-1|Location.X=1298|Location.Y=681|Color=8388608|FontID=1|IsHidden=T|Text=Beige|Name=Housing Colour
|RECORD=34|OwnerIndex=649|IndexInSheet=-1|OwnerPartId=-1|Location.X=1309|Location.Y=681|Color=8388608|FontID=1|Text=J9|Name=Designator|ReadOnlyState=1
|RECORD=41|OwnerIndex=649|IndexInSheet=-1|OwnerPartId=-1|Location.X=1309|Location.Y=618|Color=8388608|FontID=1|Text=1909763-1|Name=Comment
|RECORD=44|OwnerIndex=649
|RECORD=45|OwnerIndex=695|IndexInSheet=-1|Description=SMD, 3-Leads, Body 2.6x2.6mm, Height 1.25mm|UseComponentLibrary=T|ModelName=TECO-1909763-1_V|ModelType=PCBLIB|DatafileCount=1|ModelDatafileEntity0=TECO-1909763-1_V|ModelDatafileKind0=PCBLib|IsCurrent=T|DatalinksLocked=T|DatabaseDatalinksLocked=T
|RECORD=46|OwnerIndex=696
|RECORD=48|OwnerIndex=696
|RECORD=41|OwnerIndex=698|IndexInSheet=-1|OwnerPartId=-1|Color=8388608|FontID=1|Text=2D|Name=Available Preview Images
|RECORD=1|LibReference=CN-S-4F-RF5|ComponentDescription=Coaxial connector, 50 Ohm, -65 to 165 degC, 5-Pin THD, RoHS, Bulk|PartCount=2|DisplayModeCount=1|IndexInSheet=61|OwnerPartId=-1|Location.X=1310|Location.Y=590|CurrentPartId=1|LibraryPath=*|SourceLibraryName=Altium Content Vault|TargetFileName=*|AreaColor=11599871|Color=128|PartIDLocked=T|DesignItemId=CMP-2000-05705-1|AllPinCount=5
|RECORD=2|OwnerIndex=700|OwnerPartId=1|FormalType=1|Electrical=4|PinConglomerate=51|PinLength=10|Location.X=1350|Location.Y=550|Name=5|Designator=5|SwapIDPart=Ž&Ž1|PinPropagationDelay=0.000000E+000
|RECORD=8|OwnerIndex=700|IsNotAccesible=T|IndexInSheet=1|OwnerPartId=1|Location.X=1330|Location.Y=570|Radius=20|SecondaryRadius=20|LineWidth=1|Color=16711680|AreaColor=16777215
|RECORD=8|OwnerIndex=700|IsNotAccesible=T|IndexInSheet=2|OwnerPartId=1|Location.X=1330|Location.Y=570|Radius=4|SecondaryRadius=4|LineWidth=1|Color=16711680|AreaColor=16777215
|RECORD=2|OwnerIndex=700|OwnerPartId=1|FormalType=1|Electrical=4|PinConglomerate=50|PinLength=10|Location.X=1310|Location.Y=570|Name=1|Designator=1|PinPropagationDelay=0.000000E+000
|RECORD=2|OwnerIndex=700|OwnerPartId=1|FormalType=1|Electrical=4|PinConglomerate=51|PinLength=10|Location.X=1320|Location.Y=550|Name=2|Designator=2|PinPropagationDelay=0.000000E+000
|RECORD=2|OwnerIndex=700|OwnerPartId=1|FormalType=1|Electrical=4|PinConglomerate=51|PinLength=10|Location.X=1330|Location.Y=550|Name=3|Designator=3|PinPropagationDelay=0.000000E+000
|RECORD=2|OwnerIndex=700|OwnerPartId=1|FormalType=1|Electrical=4|PinConglomerate=51|PinLength=10|Location.X=1340|Location.Y=550|Name=4|Designator=4|PinPropagationDelay=0.000000E+000
|RECORD=6|OwnerIndex=700|IsNotAccesible=T|IndexInSheet=7|OwnerPartId=1|LineWidth=1|Color=16711680|LocationCount=5|X1=1310|Y1=550|X2=1310|Y2=590|X3=1350|Y3=590|X4=1350|Y4=550|X5=1310|Y5=550
|RECORD=6|OwnerIndex=700|IsNotAccesible=T|IndexInSheet=8|OwnerPartId=1|LineWidth=1|Color=16711680|LocationCount=2|X1=1310|Y1=570|X2=1326|Y2=570
|RECORD=41|OwnerIndex=700|IndexInSheet=9|OwnerPartId=-1|Location.X=1298|Location.Y=591|Color=8388608|FontID=1|IsHidden=T|Text=ThroughHole|Name=Mounting Technology
|RECORD=41|OwnerIndex=700|IndexInSheet=10|OwnerPartId=-1|Location.X=1298|Location.Y=591|Color=8388608|FontID=1|IsHidden=T|Text=ThroughHole,RightAngle|Name=Mounting Type
|RECORD=41|OwnerIndex=700|IndexInSheet=11|OwnerPartId=-1|Location.X=1298|Location.Y=591|Color=8388608|FontID=1|IsHidden=T|Text=-|Name=Cable Group
|RECORD=41|OwnerIndex=700|IndexInSheet=12|OwnerPartId=-1|Location.X=1298|Location.Y=591|Color=8388608|FontID=1|IsHidden=T|Text=901-143-6RFXMountingHole|Name=Catalog Drawings
|RECORD=41|OwnerIndex=700|IndexInSheet=13|OwnerPartId=-1|Location.X=1298|Location.Y=591|Color=8388608|FontID=1|IsHidden=T|Text=901-143-6RFX.igs|Name=3D Model
|RECORD=41|OwnerIndex=700|IndexInSheet=14|OwnerPartId=-1|Location.X=1298|Location.Y=591|Color=8388608|FontID=1|IsHidden=T|Text=-|Name=Series
|RECORD=41|OwnerIndex=700|IndexInSheet=15|OwnerPartId=-1|Location.X=1298|Location.Y=591|Color=8388608|FontID=1|IsHidden=T|Text=5-Pin Through Hole Device, Body 7 x 7 mm, Pitch 2.54 mm|Name=Package Description
|RECORD=41|OwnerIndex=700|IndexInSheet=16|OwnerPartId=-1|Location.X=1298|Location.Y=591|Color=8388608|FontID=1|IsHidden=T|Text=901-143-6RFX|Name=Package Reference
|RECORD=41|OwnerIndex=700|IndexInSheet=17|OwnerPartId=-1|Location.X=1298|Location.Y=591|Color=8388608|FontID=1|IsHidden=T|Text=Brass|Name=Body Material
|RECORD=41|OwnerIndex=700|IndexInSheet=18|OwnerPartId=-1|Location.X=1298|Location.Y=591|Color=8388608|FontID=1|IsHidden=T|Text=-|Name=Voltage Rating
|RECORD=41|OwnerIndex=700|IndexInSheet=19|OwnerPartId=-1|Location.X=1298|Location.Y=591|Color=8388608|FontID=1|IsHidden=T|Text=1|Name=Standard Package
|RECORD=41|OwnerIndex=700|IndexInSheet=20|OwnerPartId=-1|Location.X=1298|Location.Y=591|Color=8388608|FontID=1|IsHidden=T|Text=Jack,FemaleSocket|Name=Connector Type
|RECORD=41|OwnerIndex=700|IndexInSheet=21|OwnerPartId=-1|Location.X=1298|Location.Y=591|Color=8388608|FontID=1|IsHidden=T|Text=Threaded|Name=Fastening Type
|RECORD=41|OwnerIndex=700|IndexInSheet=22|OwnerPartId=-1|Location.X=1298|Location.Y=591|Color=8388608|FontID=1|IsHidden=T|Text=Gold|Name=Housing Color
|RECORD=41|OwnerIndex=700|IndexInSheet=23|OwnerPartId=-1|Location.X=1298|Location.Y=591|Color=8388608|FontID=1|IsHidden=T|Text=Solder|Name=Shield Termination
|RECORD=41|OwnerIndex=700|IndexInSheet=24|OwnerPartId=-1|Location.X=1298|Location.Y=591|Color=8388608|FontID=1|IsHidden=T|Text=901-143-6-RFX9011436RFXARFX1232|Name=Other Names
|RECORD=41|OwnerIndex=700|IndexInSheet=25|OwnerPartId=-1|Location.X=1298|Location.Y=591|Color=8388608|FontID=2|IsHidden=T|Text=http://www.amphenolrf.com/downloads/dl/file/id/2712/product/3102/901_143_6rfx_customer_drawing.pdf|Name=Datasheet URL
|RECORD=41|OwnerIndex=700|IndexInSheet=26|OwnerPartId=-1|Location.X=1298|Location.Y=591|Color=8388608|FontID=1|IsHidden=T|Text=CoaxialConnectors(RF)|Name=Family
|RECORD=41|OwnerIndex=700|IndexInSheet=27|OwnerPartId=-1|Location.X=1298|Location.Y=591|Color=8388608|FontID=1|IsHidden=T|Text=SMA,RFX|Name=Online Catalog
|RECORD=41|OwnerIndex=700|IndexInSheet=28|OwnerPartId=-1|Location.X=1298|Location.Y=591|Color=8388608|FontID=1|IsHidden=T|Text=18GHz|Name=Frequency - Max
|RECORD=41|OwnerIndex=700|IndexInSheet=29|OwnerPartId=-1|Location.X=1298|Location.Y=591|Color=8388608|FontID=1|IsHidden=T|Text=Solder|Name=Contact Termination
|RECORD=41|OwnerIndex=700|IndexInSheet=30|OwnerPartId=-1|Location.X=1298|Location.Y=591|Color=8388608|FontID=2|IsHidden=T|Text=http://www.amphenol.com/|Name=Manufacturer URL
|RECORD=41|OwnerIndex=700|IndexInSheet=31|OwnerPartId=-1|Location.X=1298|Location.Y=591|Color=8388608|FontID=1|IsHidden=T|Text=Amphenol|Name=Manufacturer
|RECORD=41|OwnerIndex=700|IndexInSheet=32|OwnerPartId=-1|Location.X=1298|Location.Y=591|Color=8388608|FontID=1|IsHidden=T|Text=-65°C~165°C|Name=Operating Temperature
|RECORD=41|OwnerIndex=700|IndexInSheet=33|OwnerPartId=-1|Location.X=1298|Location.Y=591|Color=8388608|FontID=1|IsHidden=T|Text=Connectors,Interconnects|Name=Category
|RECORD=41|OwnerIndex=700|IndexInSheet=34|OwnerPartId=-1|Location.X=1298|Location.Y=591|Color=8388608|FontID=1|IsHidden=T|Text=Bulk|Name=Packaging
|RECORD=41|OwnerIndex=700|IndexInSheet=35|OwnerPartId=-1|Location.X=1298|Location.Y=591|Color=8388608|FontID=1|IsHidden=T|Text=Gold|Name=Body Finish
|RECORD=41|OwnerIndex=700|IndexInSheet=36|OwnerPartId=-1|Location.X=1298|Location.Y=591|Color=8388608|FontID=1|IsHidden=T|Text=Polytetrafluoroethylene(PTFE)|Name=Dielectric Material
|RECORD=41|OwnerIndex=700|IndexInSheet=37|OwnerPartId=-1|Location.X=1298|Location.Y=591|Color=8388608|FontID=1|IsHidden=T|Text=BerylliumCopper|Name=Center Contact Material
|RECORD=41|OwnerIndex=700|IndexInSheet=38|OwnerPartId=-1|Location.X=1298|Location.Y=591|Color=8388608|FontID=1|IsHidden=T|Text=50Ohm|Name=Impedance
|RECORD=41|OwnerIndex=700|IndexInSheet=39|OwnerPartId=-1|Location.X=1298|Location.Y=591|Color=8388608|FontID=1|IsHidden=T|Text=-|Name=Features
|RECORD=41|OwnerIndex=700|IndexInSheet=40|OwnerPartId=-1|Location.X=1298|Location.Y=591|Color=8388608|FontID=1|IsHidden=T|Text=SMA|Name=Connector Style
|RECORD=41|OwnerIndex=700|IndexInSheet=41|OwnerPartId=-1|Location.X=1298|Location.Y=591|Color=8388608|FontID=1|IsHidden=T|Text=Gold|Name=Center Contact Plating
|RECORD=41|OwnerIndex=700|IndexInSheet=42|OwnerPartId=-1|Location.X=1298|Location.Y=591|Color=8388608|FontID=1|IsHidden=T|Text=Rev. C, 06/2010|Name=Datasheet Version
|RECORD=41|OwnerIndex=700|IndexInSheet=43|OwnerPartId=-1|Location.X=1298|Location.Y=591|Color=8388608|FontID=1|IsHidden=T|Text=-|Name=Ingress Protection
|RECORD=34|OwnerIndex=700|IndexInSheet=-1|OwnerPartId=-1|Location.X=1309|Location.Y=591|Color=8388608|FontID=1|Text=AN3|Name=Designator|ReadOnlyState=1
|RECORD=41|OwnerIndex=700|IndexInSheet=-1|OwnerPartId=-1|Location.X=1309|Location.Y=528|Color=8388608|FontID=1|Text=901-143-6RFX|Name=Comment
|RECORD=44|OwnerIndex=700
|RECORD=45|OwnerIndex=752|IndexInSheet=-1|Description=THD, 5-Leads, Body 7x7mm, Pitch 2.54mm|UseComponentLibrary=T|ModelName=AMPH-901-143-6RFX_V|ModelType=PCBLIB|DatafileCount=1|ModelDatafileEntity0=AMPH-901-143-6RFX_V|ModelDatafileKind0=PCBLib|IsCurrent=T|DatalinksLocked=T|DatabaseDatalinksLocked=T
|RECORD=46|OwnerIndex=753
|RECORD=48|OwnerIndex=753
|RECORD=41|OwnerIndex=755|IndexInSheet=-1|OwnerPartId=-1|Color=8388608|FontID=1|Text=2D|Name=Available Preview Images
|RECORD=17|IndexInSheet=62|OwnerPartId=-1|Style=4|ShowNetName=T|Location.X=790|Location.Y=610|Orientation=3|Color=128|FontID=1|Text=GND
|RECORD=17|IndexInSheet=63|OwnerPartId=-1|Style=4|ShowNetName=T|Location.X=1380|Location.Y=610|Orientation=3|Color=128|FontID=1|Text=GND
|RECORD=17|IndexInSheet=64|OwnerPartId=-1|Style=4|ShowNetName=T|Location.X=1380|Location.Y=290|Orientation=3|Color=128|FontID=1|Text=GND
|RECORD=17|IndexInSheet=65|OwnerPartId=-1|Style=4|ShowNetName=T|Location.X=790|Location.Y=260|Orientation=3|Color=128|FontID=1|Text=GND
|RECORD=41|IndexInSheet=66|OwnerPartId=-1|Color=8388608|FontID=1|IsHidden=T|Name=ConfigurationParameters|ReadOnlyState=1
|RECORD=41|IndexInSheet=67|OwnerPartId=-1|Color=8388608|FontID=1|IsHidden=T|Name=ConfiguratorName|ReadOnlyState=1
|RECORD=41|IndexInSheet=68|OwnerPartId=-1|Color=8388608|FontID=1|IsHidden=T|Name=VersionControl_RevNumber|ReadOnlyState=1
|RECORD=41|IndexInSheet=69|OwnerPartId=-1|Color=8388608|FontID=1|IsHidden=T|Name=IsUserConfigurable|ReadOnlyState=1
|RECORD=41|IndexInSheet=70|OwnerPartId=-1|Color=8388608|FontID=1|IsHidden=T|Name=VersionControl_ProjFolderRevNumber|ReadOnlyState=1
|RECORD=41|IndexInSheet=71|OwnerPartId=-1|Color=8388608|FontID=1|IsHidden=T|Name=SPICEModelCache|ReadOnlyState=1
|RECORD=1|LibReference=3620477901728614f2110f3aa036e68|ComponentDescription=IC BUF NON-INVERT 5.5V SOT23-5|PartCount=2|DisplayModeCount=1|IndexInSheet=72|OwnerPartId=-1|Location.X=500|Location.Y=610|CurrentPartId=1|LibraryPath=*|SourceLibraryName=Altium Content Vault|TargetFileName=*|AreaColor=11599871|Color=128|PartIDLocked=T|DesignItemId=CMP-07111-000001-1|AllPinCount=5
|RECORD=14|OwnerIndex=767|IsNotAccesible=T|OwnerPartId=1|Location.X=520|Location.Y=540|Corner.X=560|Corner.Y=620|LineWidth=1|Color=128|AreaColor=11599871|IsSolid=T
|RECORD=13|OwnerIndex=767|IsNotAccesible=T|IndexInSheet=1|OwnerPartId=1|Location.X=530|Location.Y=580|Corner.X=530|Corner.Y=560|LineWidth=1|Color=16711680
|RECORD=13|OwnerIndex=767|IsNotAccesible=T|IndexInSheet=2|OwnerPartId=1|Location.X=530|Location.Y=560|Corner.X=550|Corner.Y=570|LineWidth=1|Color=16711680
|RECORD=13|OwnerIndex=767|IsNotAccesible=T|IndexInSheet=3|OwnerPartId=1|Location.X=550|Location.Y=570|Corner.X=530|Corner.Y=580|LineWidth=1|Color=16711680
|RECORD=13|OwnerIndex=767|IsNotAccesible=T|IndexInSheet=4|OwnerPartId=1|Location.X=530|Location.Y=580|Corner.X=530|Corner.Y=570|LineWidth=1|Color=16711680
|RECORD=13|OwnerIndex=767|IsNotAccesible=T|IndexInSheet=5|OwnerPartId=1|Location.X=530|Location.Y=570|Corner.X=520|Corner.Y=570|LineWidth=1|Color=16711680
|RECORD=13|OwnerIndex=767|IsNotAccesible=T|IndexInSheet=6|OwnerPartId=1|Location.X=550|Location.Y=570|Corner.X=560|Corner.Y=570|LineWidth=1|Color=16711680
|RECORD=13|OwnerIndex=767|IsNotAccesible=T|IndexInSheet=7|OwnerPartId=1|Location.X=520|Location.Y=590|Corner.X=540|Corner.Y=590|LineWidth=1|Color=16711680
|RECORD=13|OwnerIndex=767|IsNotAccesible=T|IndexInSheet=8|OwnerPartId=1|Location.X=540|Location.Y=590|Corner.X=540|Corner.Y=580|LineWidth=1|Color=16711680
|RECORD=8|OwnerIndex=767|IsNotAccesible=T|IndexInSheet=9|OwnerPartId=1|Location.X=540|Location.Y=577|Radius=2|SecondaryRadius=2|LineWidth=1|Color=16711680
|RECORD=2|OwnerIndex=767|OwnerPartId=1|PinConglomerate=50|PinLength=20|Location.X=520|Location.Y=590|Name=O\E\|Designator=1|PinPropagationDelay=0.000000E+000
|RECORD=2|OwnerIndex=767|OwnerPartId=1|PinConglomerate=50|PinLength=20|Location.X=520|Location.Y=570|Name=A|Designator=2|PinPropagationDelay=0.000000E+000
|RECORD=2|OwnerIndex=767|OwnerPartId=1|Electrical=7|PinConglomerate=56|PinLength=20|Location.X=560|Location.Y=550|Name=GND|Designator=3|PinPropagationDelay=0.000000E+000
|RECORD=2|OwnerIndex=767|OwnerPartId=1|Electrical=2|PinConglomerate=48|PinLength=20|Location.X=560|Location.Y=570|Name=Y|Designator=4|PinPropagationDelay=0.000000E+000
|RECORD=2|OwnerIndex=767|OwnerPartId=1|Electrical=7|PinConglomerate=58|PinLength=20|Location.X=520|Location.Y=610|Name=VCC|Designator=5|PinPropagationDelay=0.000000E+000
|RECORD=41|OwnerIndex=767|IndexInSheet=15|OwnerPartId=-1|Location.X=498|Location.Y=620|Color=8388608|FontID=1|IsHidden=T|Text=+85°C|Name=Temperature Range High
|RECORD=41|OwnerIndex=767|IndexInSheet=16|OwnerPartId=-1|Location.X=498|Location.Y=620|Color=8388608|FontID=1|IsHidden=T|Text=1|Name=Number Of Circuits
|RECORD=41|OwnerIndex=767|IndexInSheet=17|OwnerPartId=-1|Location.X=498|Location.Y=620|Color=8388608|FontID=1|IsHidden=T|Text=1|Name=Number Of Outputs
|RECORD=41|OwnerIndex=767|IndexInSheet=18|OwnerPartId=-1|Location.X=498|Location.Y=620|Color=8388608|FontID=1|IsHidden=T|Text=TRUE|Name=RoHS
|RECORD=41|OwnerIndex=767|IndexInSheet=19|OwnerPartId=-1|Location.X=498|Location.Y=620|Color=8388608|FontID=1|IsHidden=T|Text=No|Name=Automotive
|RECORD=41|OwnerIndex=767|IndexInSheet=20|OwnerPartId=-1|Location.X=498|Location.Y=620|Color=8388608|FontID=1|IsHidden=T|Text=IC|Name=Category
|RECORD=41|OwnerIndex=767|IndexInSheet=21|OwnerPartId=-1|Location.X=498|Location.Y=620|Color=8388608|FontID=1|IsHidden=T|Text=+85°C|Name=Ambient Temperature Range High
|RECORD=41|OwnerIndex=767|IndexInSheet=22|OwnerPartId=-1|Location.X=498|Location.Y=620|Color=8388608|FontID=1|IsHidden=T|Text=NC7SZ125M5|Name=Manufacturer Part Number
|RECORD=41|OwnerIndex=767|IndexInSheet=23|OwnerPartId=-1|Location.X=498|Location.Y=620|Color=8388608|FontID=1|IsHidden=T|Text=Buffers|Name=Device Class L3
|RECORD=41|OwnerIndex=767|IndexInSheet=24|OwnerPartId=-1|Location.X=498|Location.Y=620|Color=8388608|FontID=1|IsHidden=T|Text=ON Semiconductor|Name=Manufacturer
|RECORD=41|OwnerIndex=767|IndexInSheet=25|OwnerPartId=-1|Location.X=498|Location.Y=620|Color=8388608|FontID=1|IsHidden=T|Text=-40°C|Name=Temperature Range Low
|RECORD=41|OwnerIndex=767|IndexInSheet=26|OwnerPartId=-1|Location.X=498|Location.Y=620|Color=8388608|FontID=1|IsHidden=T|Text=+150°C|Name=Max Junction Temp
|RECORD=41|OwnerIndex=767|IndexInSheet=27|OwnerPartId=-1|Location.X=498|Location.Y=620|Color=8388608|FontID=1|IsHidden=T|Text=Buffers & Line Drivers Buffer w/ 3-STAT O|Name=Mouser Description
|RECORD=41|OwnerIndex=767|IndexInSheet=28|OwnerPartId=-1|Location.X=498|Location.Y=620|Color=8388608|FontID=1|IsHidden=T|Text=-40°C|Name=Ambient Temperature Range Low
|RECORD=41|OwnerIndex=767|IndexInSheet=29|OwnerPartId=-1|Location.X=498|Location.Y=620|Color=8388608|FontID=1|IsHidden=T|Text=Yes|Name=Lead Free
|RECORD=41|OwnerIndex=767|IndexInSheet=30|OwnerPartId=-1|Location.X=498|Location.Y=620|Color=8388608|FontID=1|IsHidden=T|Text=0.01mm|Name=Standoff Height
|RECORD=41|OwnerIndex=767|IndexInSheet=31|OwnerPartId=-1|Location.X=498|Location.Y=620|Color=8388608|FontID=1|IsHidden=T|Text=SOT95P275X100-5|Name=Ipc Land Pattern Name
|RECORD=41|OwnerIndex=767|IndexInSheet=32|OwnerPartId=-1|Location.X=498|Location.Y=620|Color=8388608|FontID=2|IsHidden=T|Text=https://www.onsemi.com/pub/Collateral/527AH.PDF|Name=Footprint Url
|RECORD=41|OwnerIndex=767|IndexInSheet=33|OwnerPartId=-1|Location.X=498|Location.Y=620|Color=8388608|FontID=1|IsHidden=T|Text=Logic ICs|Name=Device Class L2
|RECORD=41|OwnerIndex=767|IndexInSheet=34|OwnerPartId=-1|Location.X=498|Location.Y=620|Color=8388608|FontID=1|IsHidden=T|Text=5.5V|Name=Max Supply Voltage
|RECORD=41|OwnerIndex=767|IndexInSheet=35|OwnerPartId=-1|Location.X=498|Location.Y=620|Color=8388608|FontID=1|IsHidden=T|Text=Non-Inverting|Name=Logic Function Desc
|RECORD=41|OwnerIndex=767|IndexInSheet=36|OwnerPartId=-1|Location.X=498|Location.Y=620|Color=8388608|FontID=1|IsHidden=T|Text=2uA|Name=Nominal Supply Current
|RECORD=41|OwnerIndex=767|IndexInSheet=37|OwnerPartId=-1|Location.X=498|Location.Y=620|Color=8388608|FontID=1|IsHidden=T|Text=2uA|Name=Quiescent Current
|RECORD=41|OwnerIndex=767|IndexInSheet=38|OwnerPartId=-1|Location.X=498|Location.Y=620|Color=8388608|FontID=1|IsHidden=T|Text=1|Name=Number Of Inputs
|RECORD=41|OwnerIndex=767|IndexInSheet=39|OwnerPartId=-1|Location.X=498|Location.Y=620|Color=8388608|FontID=1|IsHidden=T|Text=1.1mm|Name=Height
|RECORD=41|OwnerIndex=767|IndexInSheet=40|OwnerPartId=-1|Location.X=498|Location.Y=620|Color=8388608|FontID=1|IsHidden=T|Text=-40°C to +85°C|Name=Temperature
|RECORD=41|OwnerIndex=767|IndexInSheet=41|OwnerPartId=-1|Location.X=498|Location.Y=620|Color=8388608|FontID=1|IsHidden=T|Text=1.65V|Name=Min Supply Voltage
|RECORD=41|OwnerIndex=767|IndexInSheet=42|OwnerPartId=-1|Location.X=498|Location.Y=620|Color=8388608|FontID=1|IsHidden=T|Text=Integrated Circuits (ICs)|Name=Device Class L1
|RECORD=41|OwnerIndex=767|IndexInSheet=43|OwnerPartId=-1|Location.X=498|Location.Y=620|Color=8388608|FontID=1|IsHidden=T|Text=2.6ns|Name=Propagation Delay
|RECORD=41|OwnerIndex=767|IndexInSheet=44|OwnerPartId=-1|Location.X=498|Location.Y=620|Color=8388608|FontID=2|IsHidden=T|Text=https://www.onsemi.com/pub/Collateral/NC7SZ125-D.PDF|Name=ComponentLink2URL
|RECORD=41|OwnerIndex=767|IndexInSheet=45|OwnerPartId=-1|Location.X=498|Location.Y=620|Color=8388608|FontID=1|IsHidden=T|Text=IC BUF NON-INVERT 5.5V SOT23-5|Name=Digikey Description
|RECORD=41|OwnerIndex=767|IndexInSheet=46|OwnerPartId=-1|Location.X=498|Location.Y=620|Color=8388608|FontID=1|IsHidden=T|Text=318BQ|Name=Package
|RECORD=41|OwnerIndex=767|IndexInSheet=47|OwnerPartId=-1|Location.X=498|Location.Y=620|Color=8388608|FontID=2|IsHidden=T|Text=https://octopart.com/nc7sz125m5-on+semiconductor-84330746|Name=Octopart
|RECORD=41|OwnerIndex=767|IndexInSheet=48|OwnerPartId=-1|Location.X=498|Location.Y=620|Color=8388608|FontID=1|IsHidden=T|Text=Datasheet|Name=ComponentLink2Description
|RECORD=34|OwnerIndex=767|IndexInSheet=-1|OwnerPartId=-1|Location.X=519|Location.Y=620|Color=8388608|FontID=1|Text=U6|Name=Designator|ReadOnlyState=1
|RECORD=41|OwnerIndex=767|IndexInSheet=-1|OwnerPartId=1|Location.X=519|Location.Y=530|Color=8388608|FontID=1|Text=NC7SZ125M5|Name=Comment
|RECORD=44|OwnerIndex=767
|RECORD=45|OwnerIndex=824|IndexInSheet=-1|UseComponentLibrary=T|ModelName=FP-318BQ-MFG|ModelType=PCBLIB|DatafileCount=1|ModelDatafileEntity0=FP-318BQ-MFG|ModelDatafileKind0=PCBLib|IsCurrent=T|DatalinksLocked=T|DatabaseDatalinksLocked=T
|RECORD=46|OwnerIndex=825
|RECORD=48|OwnerIndex=825
|RECORD=45|OwnerIndex=824|IndexInSheet=-1|UseComponentLibrary=T|ModelName=FP-318BQ-IPC_C|ModelType=PCBLIB|DatafileCount=1|ModelDatafileEntity0=FP-318BQ-IPC_C|ModelDatafileKind0=PCBLib|DatalinksLocked=T|DatabaseDatalinksLocked=T
|RECORD=46|OwnerIndex=828
|RECORD=48|OwnerIndex=828
|RECORD=45|OwnerIndex=824|IndexInSheet=-1|UseComponentLibrary=T|ModelName=FP-318BQ-IPC_B|ModelType=PCBLIB|DatafileCount=1|ModelDatafileEntity0=FP-318BQ-IPC_B|ModelDatafileKind0=PCBLib|DatalinksLocked=T|DatabaseDatalinksLocked=T
|RECORD=46|OwnerIndex=831
|RECORD=48|OwnerIndex=831
|RECORD=45|OwnerIndex=824|IndexInSheet=-1|UseComponentLibrary=T|ModelName=FP-318BQ-IPC_A|ModelType=PCBLIB|DatafileCount=1|ModelDatafileEntity0=FP-318BQ-IPC_A|ModelDatafileKind0=PCBLib|DatalinksLocked=T|DatabaseDatalinksLocked=T
|RECORD=46|OwnerIndex=834
|RECORD=48|OwnerIndex=834
|RECORD=1|LibReference=RES-2|ComponentDescription=General Purpose Chip Resistor, 49.9 Ohm, +/- 1%, -55 to 155 degC, 0603 (1608 Metric), RoHS, Tape and Reel|PartCount=2|DisplayModeCount=1|IndexInSheet=73|OwnerPartId=-1|Location.X=620|Location.Y=570|CurrentPartId=1|LibraryPath=*|SourceLibraryName=Altium Content Vault|TargetFileName=*|AreaColor=11599871|Color=128|PartIDLocked=T|DesignItemId=CMP-1659-00036-1|AllPinCount=2
|RECORD=2|OwnerIndex=837|OwnerPartId=1|FormalType=1|Electrical=4|PinConglomerate=32|PinLength=10|Location.X=640|Location.Y=570|Name=2|Designator=2|PinPropagationDelay=0.000000E+000
|RECORD=2|OwnerIndex=837|OwnerPartId=1|FormalType=1|Electrical=4|PinConglomerate=34|PinLength=10|Location.X=620|Location.Y=570|Name=1|Designator=1|PinPropagationDelay=0.000000E+000
|RECORD=6|OwnerIndex=837|IsNotAccesible=T|IndexInSheet=2|OwnerPartId=1|LineWidth=1|Color=16711680|LocationCount=10|X1=640|Y1=570|X2=636|Y2=570|X3=635|Y3=568|X4=633|Y4=572|X5=631|Y5=568|X6=629|Y6=572|X7=627|Y7=568|X8=625|Y8=572|X9=624|Y9=570|X10=620|Y10=570
|RECORD=41|OwnerIndex=837|IndexInSheet=3|OwnerPartId=-1|Location.X=608|Location.Y=585|Color=8388608|FontID=1|IsHidden=T|Text=0603|Name=PackageReference
|RECORD=41|OwnerIndex=837|IndexInSheet=4|OwnerPartId=-1|Location.X=608|Location.Y=585|Color=8388608|FontID=1|IsHidden=T|Text=Tray|Name=Packaging
|RECORD=41|OwnerIndex=837|IndexInSheet=5|OwnerPartId=-1|Location.X=608|Location.Y=585|Color=8388608|FontID=1|IsHidden=T|Text=Datasheet|Name=ComponentLink2Description
|RECORD=41|OwnerIndex=837|IndexInSheet=6|OwnerPartId=-1|Location.X=608|Location.Y=585|Color=8388608|FontID=1|IsHidden=T|Text=Manufacturer URL|Name=ComponentLink1Description
|RECORD=41|OwnerIndex=837|IndexInSheet=7|OwnerPartId=-1|Location.X=608|Location.Y=585|Color=8388608|FontID=2|IsHidden=T|Text=https://datasheet.ciiva.com/11808/0900766b80f96399-11808223.pdf|Name=ComponentLink2URL
|RECORD=41|OwnerIndex=837|IndexInSheet=8|OwnerPartId=-1|Location.X=608|Location.Y=585|Color=8388608|FontID=1|IsHidden=T|Text=true|Name=RoHSCompliant
|RECORD=41|OwnerIndex=837|IndexInSheet=9|OwnerPartId=-1|Location.X=608|Location.Y=585|Color=8388608|FontID=1|IsHidden=T|Text=85 degC|Name=Max Operating Temperature
|RECORD=41|OwnerIndex=837|IndexInSheet=10|OwnerPartId=-1|Location.X=608|Location.Y=585|Color=8388608|FontID=1|IsHidden=T|Text=3.63 V|Name=Max Supply Voltage
|RECORD=41|OwnerIndex=837|IndexInSheet=11|OwnerPartId=-1|Location.X=608|Location.Y=585|Color=8388608|FontID=2|IsHidden=T|Text=http://www.yageo.com/|Name=ComponentLink1URL
|RECORD=41|OwnerIndex=837|IndexInSheet=12|OwnerPartId=-1|Location.X=608|Location.Y=585|Color=8388608|FontID=1|IsHidden=T|Text=2-Pin Surface Mount Device, Body 1.6 x 0.8 mm|Name=PackageDescription
|RECORD=41|OwnerIndex=837|IndexInSheet=13|OwnerPartId=-1|Location.X=608|Location.Y=585|Color=8388608|FontID=1|IsHidden=T|Text=LQFP|Name=Case\Package
|RECORD=41|OwnerIndex=837|IndexInSheet=14|OwnerPartId=-1|Location.X=608|Location.Y=585|Color=8388608|FontID=1|IsHidden=T|Text=Rev. 4, 04/2009|Name=DatasheetVersion
|RECORD=41|OwnerIndex=837|IndexInSheet=15|OwnerPartId=-1|Location.X=608|Location.Y=585|Color=8388608|FontID=1|IsHidden=T|Text=-40 degC|Name=Min Operating Temperature
|RECORD=41|OwnerIndex=837|IndexInSheet=16|OwnerPartId=-1|Location.X=608|Location.Y=585|Color=8388608|FontID=1|IsHidden=T|Text=SPI|Name=Interface
|RECORD=41|OwnerIndex=837|IndexInSheet=17|OwnerPartId=-1|Location.X=608|Location.Y=585|Color=8388608|FontID=1|IsHidden=T|Text=250|Name=Package Quantity
|RECORD=41|OwnerIndex=837|IndexInSheet=18|OwnerPartId=-1|Location.X=608|Location.Y=585|Color=8388608|FontID=1|IsHidden=T|Text=2.97 V|Name=Min Supply Voltage
|RECORD=41|OwnerIndex=837|IndexInSheet=19|OwnerPartId=-1|Location.X=608|Location.Y=585|Color=8388608|FontID=1|IsHidden=T|Text=48|Name=Pins
|RECORD=34|OwnerIndex=837|IndexInSheet=-1|OwnerPartId=-1|Location.X=619|Location.Y=573|Color=8388608|FontID=1|Text=R14|Name=Designator|ReadOnlyState=1
|RECORD=41|OwnerIndex=837|IndexInSheet=-1|OwnerPartId=-1|Location.X=619|Location.Y=557|Color=8388608|FontID=1|Text=49.9R|Name=Comment
|RECORD=44|OwnerIndex=837
|RECORD=45|OwnerIndex=862|IndexInSheet=-1|Description=Chip Resistor, 2-Leads, Body 1.70x0.90mm, IPC Medium Density|UseComponentLibrary=T|ModelName=RESC1608X55X25NL10T15|ModelType=PCBLIB|DatafileCount=1|ModelDatafileEntity0=RESC1608X55X25NL10T15|ModelDatafileKind0=PCBLib|IsCurrent=T|DatalinksLocked=T|DatabaseDatalinksLocked=T
|RECORD=46|OwnerIndex=863
|RECORD=48|OwnerIndex=863
|RECORD=41|OwnerIndex=865|IndexInSheet=-1|OwnerPartId=-1|Color=8388608|FontID=1|IsHidden=T|Text=2D|Name=Available Preview Images
|RECORD=45|OwnerIndex=862|IndexInSheet=-1|Description=Chip Resistor, 2-Leads, Body 1.70x0.90mm, IPC Low Density|UseComponentLibrary=T|ModelName=RESC1608X55X25ML10T15|ModelType=PCBLIB|DatafileCount=1|ModelDatafileEntity0=RESC1608X55X25ML10T15|ModelDatafileKind0=PCBLib|DatalinksLocked=T|DatabaseDatalinksLocked=T
|RECORD=46|OwnerIndex=867
|RECORD=48|OwnerIndex=867
|RECORD=41|OwnerIndex=869|IndexInSheet=-1|OwnerPartId=-1|Color=8388608|FontID=1|IsHidden=T|Text=2D|Name=Available Preview Images
|RECORD=45|OwnerIndex=862|IndexInSheet=-1|Description=Chip Resistor, 2-Leads, Body 1.70x0.90mm, IPC High Density|UseComponentLibrary=T|ModelName=RESC1608X55X25LL10T15|ModelType=PCBLIB|DatafileCount=1|ModelDatafileEntity0=RESC1608X55X25LL10T15|ModelDatafileKind0=PCBLib|DatalinksLocked=T|DatabaseDatalinksLocked=T
|RECORD=46|OwnerIndex=871
|RECORD=48|OwnerIndex=871
|RECORD=41|OwnerIndex=873|IndexInSheet=-1|OwnerPartId=-1|Color=8388608|FontID=1|IsHidden=T|Text=2D|Name=Available Preview Images
|RECORD=17|IndexInSheet=74|OwnerPartId=-1|Style=4|ShowNetName=T|Location.X=610|Location.Y=470|Orientation=3|Color=128|FontID=1|Text=GND
|RECORD=17|IndexInSheet=75|OwnerPartId=-1|Style=4|ShowNetName=T|Location.X=480|Location.Y=470|Orientation=3|Color=128|FontID=1|Text=GND
|RECORD=1|LibReference=CAP|ComponentDescription=C0603X104K5RACAUTO|PartCount=2|DisplayModeCount=2|IndexInSheet=76|OwnerPartId=-1|Location.X=440|Location.Y=520|Orientation=3|CurrentPartId=1|SourceLibraryName=Altium Content Vault|TargetFileName=*|AreaColor=11599871|Color=128|PartIDLocked=F|DesignItemId=CMP-2006-00003-1|AllPinCount=2
|RECORD=2|OwnerIndex=877|OwnerPartId=1|OwnerPartDisplayMode=1|FormalType=1|Electrical=4|PinConglomerate=33|PinLength=10|Location.X=430|Location.Y=520|Name=1|Designator=1|PinPropagationDelay=0.000000E+000
|RECORD=2|OwnerIndex=877|OwnerPartId=1|OwnerPartDisplayMode=1|FormalType=1|Electrical=4|PinConglomerate=35|PinLength=10|Location.X=430|Location.Y=510|Name=2|Designator=2|PinPropagationDelay=0.000000E+000
|RECORD=13|OwnerIndex=877|IsNotAccesible=T|IndexInSheet=2|OwnerPartId=1|OwnerPartDisplayMode=1|Location.X=422|Location.Y=520|Corner.X=438|Corner.Y=520|LineWidth=1|Color=16711680
|RECORD=13|OwnerIndex=877|IsNotAccesible=T|IndexInSheet=3|OwnerPartId=1|OwnerPartDisplayMode=1|Location.X=430|Location.Y=516|Corner.X=430|Corner.Y=510|LineWidth=1|Color=16711680
|RECORD=12|OwnerIndex=877|IsNotAccesible=T|IndexInSheet=4|OwnerPartId=1|OwnerPartDisplayMode=1|Location.X=430|Location.Y=500|Radius=16|LineWidth=1|StartAngle=61.000|EndAngle=90.000|Color=16711680
|RECORD=12|OwnerIndex=877|IsNotAccesible=T|IndexInSheet=5|OwnerPartId=1|OwnerPartDisplayMode=1|Location.X=430|Location.Y=500|Radius=16|LineWidth=1|StartAngle=90.000|EndAngle=119.000|Color=16711680
|RECORD=2|OwnerIndex=877|OwnerPartId=1|FormalType=1|Electrical=4|PinConglomerate=33|PinLength=10|Location.X=430|Location.Y=520|Name=1|Designator=1|PinPropagationDelay=0.000000E+000
|RECORD=2|OwnerIndex=877|OwnerPartId=1|FormalType=1|Electrical=4|PinConglomerate=35|PinLength=10|Location.X=430|Location.Y=510|Name=2|Designator=2|PinPropagationDelay=0.000000E+000
|RECORD=13|OwnerIndex=877|IsNotAccesible=T|IndexInSheet=8|OwnerPartId=1|Location.X=438|Location.Y=513|Corner.X=422|Corner.Y=513|LineWidth=1|Color=16711680
|RECORD=13|OwnerIndex=877|IsNotAccesible=T|IndexInSheet=9|OwnerPartId=1|Location.X=422|Location.Y=517|Corner.X=438|Corner.Y=517|LineWidth=1|Color=16711680
|RECORD=6|OwnerIndex=877|IsNotAccesible=T|IndexInSheet=10|OwnerPartId=1|LineWidth=1|Color=16711680|LocationCount=2|X1=430|Y1=520|X2=430|Y2=517
|RECORD=6|OwnerIndex=877|IsNotAccesible=T|IndexInSheet=11|OwnerPartId=1|LineWidth=1|Color=16711680|LocationCount=2|X1=430|Y1=510|X2=430|Y2=513
|RECORD=41|OwnerIndex=877|IndexInSheet=12|OwnerPartId=-1|Location.X=421|Location.Y=532|Color=8388608|FontID=1|IsHidden=T|Text=Kemet|Name=Manufacturer
|RECORD=41|OwnerIndex=877|IndexInSheet=13|OwnerPartId=-1|Location.X=421|Location.Y=532|Color=8388608|FontID=1|IsHidden=T|Text=C0603X104K5RACAUTO|Name=Part Number
|RECORD=34|OwnerIndex=877|IndexInSheet=-1|OwnerPartId=-1|Location.X=439|Location.Y=507|Color=8388608|FontID=4|Text=C26|Name=Designator|ReadOnlyState=1
|RECORD=41|OwnerIndex=877|IndexInSheet=-1|OwnerPartId=-1|Location.X=439|Location.Y=493|Color=8388608|FontID=4|Text=0.1uF|Name=Comment
|RECORD=44|OwnerIndex=877
|RECORD=45|OwnerIndex=898|IndexInSheet=-1|Description=Chip Capacitor, 2-Leads, Body 1.60x0.80mm, IPC Low Density|UseComponentLibrary=T|ModelName=CAPC1608X87X45ML20T05|ModelType=PCBLIB|DatafileCount=1|ModelDatafileEntity0=CAPC1608X87X45ML20T05|ModelDatafileKind0=PCBLib|IsCurrent=T|DatalinksLocked=T|DatabaseDatalinksLocked=T
|RECORD=46|OwnerIndex=899
|RECORD=48|OwnerIndex=899
|RECORD=41|OwnerIndex=901|IndexInSheet=-1|OwnerPartId=-1|Color=8388608|FontID=1|Text=2D|Name=Available Preview Images
|RECORD=45|OwnerIndex=898|IndexInSheet=-1|Description=Chip Capacitor, 2-Leads, Body 1.60x0.80mm, IPC High Density|UseComponentLibrary=T|ModelName=CAPC1608X87X45LL20T05|ModelType=PCBLIB|DatafileCount=1|ModelDatafileEntity0=CAPC1608X87X45LL20T05|ModelDatafileKind0=PCBLib|DatalinksLocked=T|DatabaseDatalinksLocked=T
|RECORD=46|OwnerIndex=903
|RECORD=48|OwnerIndex=903
|RECORD=41|OwnerIndex=905|IndexInSheet=-1|OwnerPartId=-1|Color=8388608|FontID=1|Text=2D|Name=Available Preview Images
|RECORD=45|OwnerIndex=898|IndexInSheet=-1|Description=Chip Capacitor, 2-Leads, Body 1.60x0.80mm, IPC Medium Density|UseComponentLibrary=T|ModelName=CAPC1608X87X45NL20T05|ModelType=PCBLIB|DatafileCount=1|ModelDatafileEntity0=CAPC1608X87X45NL20T05|ModelDatafileKind0=PCBLib|DatalinksLocked=T|DatabaseDatalinksLocked=T
|RECORD=46|OwnerIndex=907
|RECORD=48|OwnerIndex=907
|RECORD=41|OwnerIndex=909|IndexInSheet=-1|OwnerPartId=-1|Color=8388608|FontID=1|Text=2D|Name=Available Preview Images
|RECORD=17|IndexInSheet=77|OwnerPartId=-1|Style=4|ShowNetName=T|Location.X=430|Location.Y=470|Orientation=3|Color=128|FontID=1|Text=GND
|RECORD=17|IndexInSheet=78|OwnerPartId=-1|ShowNetName=T|Location.X=430|Location.Y=650|Orientation=1|Color=128|FontID=1|Text=+3.3V
|RECORD=1|LibReference=3620477901728614f2110f3aa036e68|ComponentDescription=IC BUF NON-INVERT 5.5V SOT23-5|PartCount=2|DisplayModeCount=1|IndexInSheet=79|OwnerPartId=-1|Location.X=500|Location.Y=260|CurrentPartId=1|LibraryPath=*|SourceLibraryName=Altium Content Vault|TargetFileName=*|AreaColor=11599871|Color=128|PartIDLocked=T|DesignItemId=CMP-07111-000001-1|AllPinCount=5
|RECORD=14|OwnerIndex=913|IsNotAccesible=T|OwnerPartId=1|Location.X=520|Location.Y=190|Corner.X=560|Corner.Y=270|LineWidth=1|Color=128|AreaColor=11599871|IsSolid=T
|RECORD=13|OwnerIndex=913|IsNotAccesible=T|IndexInSheet=1|OwnerPartId=1|Location.X=530|Location.Y=230|Corner.X=530|Corner.Y=210|LineWidth=1|Color=16711680
|RECORD=13|OwnerIndex=913|IsNotAccesible=T|IndexInSheet=2|OwnerPartId=1|Location.X=530|Location.Y=210|Corner.X=550|Corner.Y=220|LineWidth=1|Color=16711680
|RECORD=13|OwnerIndex=913|IsNotAccesible=T|IndexInSheet=3|OwnerPartId=1|Location.X=550|Location.Y=220|Corner.X=530|Corner.Y=230|LineWidth=1|Color=16711680
|RECORD=13|OwnerIndex=913|IsNotAccesible=T|IndexInSheet=4|OwnerPartId=1|Location.X=530|Location.Y=230|Corner.X=530|Corner.Y=220|LineWidth=1|Color=16711680
|RECORD=13|OwnerIndex=913|IsNotAccesible=T|IndexInSheet=5|OwnerPartId=1|Location.X=530|Location.Y=220|Corner.X=520|Corner.Y=220|LineWidth=1|Color=16711680
|RECORD=13|OwnerIndex=913|IsNotAccesible=T|IndexInSheet=6|OwnerPartId=1|Location.X=550|Location.Y=220|Corner.X=560|Corner.Y=220|LineWidth=1|Color=16711680
|RECORD=13|OwnerIndex=913|IsNotAccesible=T|IndexInSheet=7|OwnerPartId=1|Location.X=520|Location.Y=240|Corner.X=540|Corner.Y=240|LineWidth=1|Color=16711680
|RECORD=13|OwnerIndex=913|IsNotAccesible=T|IndexInSheet=8|OwnerPartId=1|Location.X=540|Location.Y=240|Corner.X=540|Corner.Y=230|LineWidth=1|Color=16711680
|RECORD=8|OwnerIndex=913|IsNotAccesible=T|IndexInSheet=9|OwnerPartId=1|Location.X=540|Location.Y=227|Radius=2|SecondaryRadius=2|LineWidth=1|Color=16711680
|RECORD=2|OwnerIndex=913|OwnerPartId=1|PinConglomerate=50|PinLength=20|Location.X=520|Location.Y=240|Name=O\E\|Designator=1|PinPropagationDelay=0.000000E+000
|RECORD=2|OwnerIndex=913|OwnerPartId=1|PinConglomerate=50|PinLength=20|Location.X=520|Location.Y=220|Name=A|Designator=2|PinPropagationDelay=0.000000E+000
|RECORD=2|OwnerIndex=913|OwnerPartId=1|Electrical=7|PinConglomerate=56|PinLength=20|Location.X=560|Location.Y=200|Name=GND|Designator=3|PinPropagationDelay=0.000000E+000
|RECORD=2|OwnerIndex=913|OwnerPartId=1|Electrical=2|PinConglomerate=48|PinLength=20|Location.X=560|Location.Y=220|Name=Y|Designator=4|PinPropagationDelay=0.000000E+000
|RECORD=2|OwnerIndex=913|OwnerPartId=1|Electrical=7|PinConglomerate=58|PinLength=20|Location.X=520|Location.Y=260|Name=VCC|Designator=5|PinPropagationDelay=0.000000E+000
|RECORD=41|OwnerIndex=913|IndexInSheet=15|OwnerPartId=-1|Location.X=498|Location.Y=270|Color=8388608|FontID=1|IsHidden=T|Text=+85°C|Name=Temperature Range High
|RECORD=41|OwnerIndex=913|IndexInSheet=16|OwnerPartId=-1|Location.X=498|Location.Y=270|Color=8388608|FontID=1|IsHidden=T|Text=1|Name=Number Of Circuits
|RECORD=41|OwnerIndex=913|IndexInSheet=17|OwnerPartId=-1|Location.X=498|Location.Y=270|Color=8388608|FontID=1|IsHidden=T|Text=1|Name=Number Of Outputs
|RECORD=41|OwnerIndex=913|IndexInSheet=18|OwnerPartId=-1|Location.X=498|Location.Y=270|Color=8388608|FontID=1|IsHidden=T|Text=TRUE|Name=RoHS
|RECORD=41|OwnerIndex=913|IndexInSheet=19|OwnerPartId=-1|Location.X=498|Location.Y=270|Color=8388608|FontID=1|IsHidden=T|Text=No|Name=Automotive
|RECORD=41|OwnerIndex=913|IndexInSheet=20|OwnerPartId=-1|Location.X=498|Location.Y=270|Color=8388608|FontID=1|IsHidden=T|Text=IC|Name=Category
|RECORD=41|OwnerIndex=913|IndexInSheet=21|OwnerPartId=-1|Location.X=498|Location.Y=270|Color=8388608|FontID=1|IsHidden=T|Text=+85°C|Name=Ambient Temperature Range High
|RECORD=41|OwnerIndex=913|IndexInSheet=22|OwnerPartId=-1|Location.X=498|Location.Y=270|Color=8388608|FontID=1|IsHidden=T|Text=NC7SZ125M5|Name=Manufacturer Part Number
|RECORD=41|OwnerIndex=913|IndexInSheet=23|OwnerPartId=-1|Location.X=498|Location.Y=270|Color=8388608|FontID=1|IsHidden=T|Text=Buffers|Name=Device Class L3
|RECORD=41|OwnerIndex=913|IndexInSheet=24|OwnerPartId=-1|Location.X=498|Location.Y=270|Color=8388608|FontID=1|IsHidden=T|Text=ON Semiconductor|Name=Manufacturer
|RECORD=41|OwnerIndex=913|IndexInSheet=25|OwnerPartId=-1|Location.X=498|Location.Y=270|Color=8388608|FontID=1|IsHidden=T|Text=-40°C|Name=Temperature Range Low
|RECORD=41|OwnerIndex=913|IndexInSheet=26|OwnerPartId=-1|Location.X=498|Location.Y=270|Color=8388608|FontID=1|IsHidden=T|Text=+150°C|Name=Max Junction Temp
|RECORD=41|OwnerIndex=913|IndexInSheet=27|OwnerPartId=-1|Location.X=498|Location.Y=270|Color=8388608|FontID=1|IsHidden=T|Text=Buffers & Line Drivers Buffer w/ 3-STAT O|Name=Mouser Description
|RECORD=41|OwnerIndex=913|IndexInSheet=28|OwnerPartId=-1|Location.X=498|Location.Y=270|Color=8388608|FontID=1|IsHidden=T|Text=-40°C|Name=Ambient Temperature Range Low
|RECORD=41|OwnerIndex=913|IndexInSheet=29|OwnerPartId=-1|Location.X=498|Location.Y=270|Color=8388608|FontID=1|IsHidden=T|Text=Yes|Name=Lead Free
|RECORD=41|OwnerIndex=913|IndexInSheet=30|OwnerPartId=-1|Location.X=498|Location.Y=270|Color=8388608|FontID=1|IsHidden=T|Text=0.01mm|Name=Standoff Height
|RECORD=41|OwnerIndex=913|IndexInSheet=31|OwnerPartId=-1|Location.X=498|Location.Y=270|Color=8388608|FontID=1|IsHidden=T|Text=SOT95P275X100-5|Name=Ipc Land Pattern Name
|RECORD=41|OwnerIndex=913|IndexInSheet=32|OwnerPartId=-1|Location.X=498|Location.Y=270|Color=8388608|FontID=2|IsHidden=T|Text=https://www.onsemi.com/pub/Collateral/527AH.PDF|Name=Footprint Url
|RECORD=41|OwnerIndex=913|IndexInSheet=33|OwnerPartId=-1|Location.X=498|Location.Y=270|Color=8388608|FontID=1|IsHidden=T|Text=Logic ICs|Name=Device Class L2
|RECORD=41|OwnerIndex=913|IndexInSheet=34|OwnerPartId=-1|Location.X=498|Location.Y=270|Color=8388608|FontID=1|IsHidden=T|Text=5.5V|Name=Max Supply Voltage
|RECORD=41|OwnerIndex=913|IndexInSheet=35|OwnerPartId=-1|Location.X=498|Location.Y=270|Color=8388608|FontID=1|IsHidden=T|Text=Non-Inverting|Name=Logic Function Desc
|RECORD=41|OwnerIndex=913|IndexInSheet=36|OwnerPartId=-1|Location.X=498|Location.Y=270|Color=8388608|FontID=1|IsHidden=T|Text=2uA|Name=Nominal Supply Current
|RECORD=41|OwnerIndex=913|IndexInSheet=37|OwnerPartId=-1|Location.X=498|Location.Y=270|Color=8388608|FontID=1|IsHidden=T|Text=2uA|Name=Quiescent Current
|RECORD=41|OwnerIndex=913|IndexInSheet=38|OwnerPartId=-1|Location.X=498|Location.Y=270|Color=8388608|FontID=1|IsHidden=T|Text=1|Name=Number Of Inputs
|RECORD=41|OwnerIndex=913|IndexInSheet=39|OwnerPartId=-1|Location.X=498|Location.Y=270|Color=8388608|FontID=1|IsHidden=T|Text=1.1mm|Name=Height
|RECORD=41|OwnerIndex=913|IndexInSheet=40|OwnerPartId=-1|Location.X=498|Location.Y=270|Color=8388608|FontID=1|IsHidden=T|Text=-40°C to +85°C|Name=Temperature
|RECORD=41|OwnerIndex=913|IndexInSheet=41|OwnerPartId=-1|Location.X=498|Location.Y=270|Color=8388608|FontID=1|IsHidden=T|Text=1.65V|Name=Min Supply Voltage
|RECORD=41|OwnerIndex=913|IndexInSheet=42|OwnerPartId=-1|Location.X=498|Location.Y=270|Color=8388608|FontID=1|IsHidden=T|Text=Integrated Circuits (ICs)|Name=Device Class L1
|RECORD=41|OwnerIndex=913|IndexInSheet=43|OwnerPartId=-1|Location.X=498|Location.Y=270|Color=8388608|FontID=1|IsHidden=T|Text=2.6ns|Name=Propagation Delay
|RECORD=41|OwnerIndex=913|IndexInSheet=44|OwnerPartId=-1|Location.X=498|Location.Y=270|Color=8388608|FontID=2|IsHidden=T|Text=https://www.onsemi.com/pub/Collateral/NC7SZ125-D.PDF|Name=ComponentLink2URL
|RECORD=41|OwnerIndex=913|IndexInSheet=45|OwnerPartId=-1|Location.X=498|Location.Y=270|Color=8388608|FontID=1|IsHidden=T|Text=IC BUF NON-INVERT 5.5V SOT23-5|Name=Digikey Description
|RECORD=41|OwnerIndex=913|IndexInSheet=46|OwnerPartId=-1|Location.X=498|Location.Y=270|Color=8388608|FontID=1|IsHidden=T|Text=318BQ|Name=Package
|RECORD=41|OwnerIndex=913|IndexInSheet=47|OwnerPartId=-1|Location.X=498|Location.Y=270|Color=8388608|FontID=2|IsHidden=T|Text=https://octopart.com/nc7sz125m5-on+semiconductor-84330746|Name=Octopart
|RECORD=41|OwnerIndex=913|IndexInSheet=48|OwnerPartId=-1|Location.X=498|Location.Y=270|Color=8388608|FontID=1|IsHidden=T|Text=Datasheet|Name=ComponentLink2Description
|RECORD=34|OwnerIndex=913|IndexInSheet=-1|OwnerPartId=-1|Location.X=519|Location.Y=270|Color=8388608|FontID=1|Text=U11|Name=Designator|ReadOnlyState=1
|RECORD=41|OwnerIndex=913|IndexInSheet=-1|OwnerPartId=1|Location.X=519|Location.Y=180|Color=8388608|FontID=1|Text=NC7SZ125M5|Name=Comment
|RECORD=44|OwnerIndex=913
|RECORD=45|OwnerIndex=970|IndexInSheet=-1|UseComponentLibrary=T|ModelName=FP-318BQ-MFG|ModelType=PCBLIB|DatafileCount=1|ModelDatafileEntity0=FP-318BQ-MFG|ModelDatafileKind0=PCBLib|IsCurrent=T|DatalinksLocked=T|DatabaseDatalinksLocked=T
|RECORD=46|OwnerIndex=971
|RECORD=48|OwnerIndex=971
|RECORD=45|OwnerIndex=970|IndexInSheet=-1|UseComponentLibrary=T|ModelName=FP-318BQ-IPC_C|ModelType=PCBLIB|DatafileCount=1|ModelDatafileEntity0=FP-318BQ-IPC_C|ModelDatafileKind0=PCBLib|DatalinksLocked=T|DatabaseDatalinksLocked=T
|RECORD=46|OwnerIndex=974
|RECORD=48|OwnerIndex=974
|RECORD=45|OwnerIndex=970|IndexInSheet=-1|UseComponentLibrary=T|ModelName=FP-318BQ-IPC_B|ModelType=PCBLIB|DatafileCount=1|ModelDatafileEntity0=FP-318BQ-IPC_B|ModelDatafileKind0=PCBLib|DatalinksLocked=T|DatabaseDatalinksLocked=T
|RECORD=46|OwnerIndex=977
|RECORD=48|OwnerIndex=977
|RECORD=45|OwnerIndex=970|IndexInSheet=-1|UseComponentLibrary=T|ModelName=FP-318BQ-IPC_A|ModelType=PCBLIB|DatafileCount=1|ModelDatafileEntity0=FP-318BQ-IPC_A|ModelDatafileKind0=PCBLib|DatalinksLocked=T|DatabaseDatalinksLocked=T
|RECORD=46|OwnerIndex=980
|RECORD=48|OwnerIndex=980
|RECORD=1|LibReference=RES-2|ComponentDescription=General Purpose Chip Resistor, 49.9 Ohm, +/- 1%, -55 to 155 degC, 0603 (1608 Metric), RoHS, Tape and Reel|PartCount=2|DisplayModeCount=1|IndexInSheet=80|OwnerPartId=-1|Location.X=620|Location.Y=220|CurrentPartId=1|LibraryPath=*|SourceLibraryName=Altium Content Vault|TargetFileName=*|AreaColor=11599871|Color=128|PartIDLocked=T|DesignItemId=CMP-1659-00036-1|AllPinCount=2
|RECORD=2|OwnerIndex=983|OwnerPartId=1|FormalType=1|Electrical=4|PinConglomerate=32|PinLength=10|Location.X=640|Location.Y=220|Name=2|Designator=2|PinPropagationDelay=0.000000E+000
|RECORD=2|OwnerIndex=983|OwnerPartId=1|FormalType=1|Electrical=4|PinConglomerate=34|PinLength=10|Location.X=620|Location.Y=220|Name=1|Designator=1|PinPropagationDelay=0.000000E+000
|RECORD=6|OwnerIndex=983|IsNotAccesible=T|IndexInSheet=2|OwnerPartId=1|LineWidth=1|Color=16711680|LocationCount=10|X1=640|Y1=220|X2=636|Y2=220|X3=635|Y3=218|X4=633|Y4=222|X5=631|Y5=218|X6=629|Y6=222|X7=627|Y7=218|X8=625|Y8=222|X9=624|Y9=220|X10=620|Y10=220
|RECORD=41|OwnerIndex=983|IndexInSheet=3|OwnerPartId=-1|Location.X=608|Location.Y=235|Color=8388608|FontID=1|IsHidden=T|Text=0603|Name=PackageReference
|RECORD=41|OwnerIndex=983|IndexInSheet=4|OwnerPartId=-1|Location.X=608|Location.Y=235|Color=8388608|FontID=1|IsHidden=T|Text=Tray|Name=Packaging
|RECORD=41|OwnerIndex=983|IndexInSheet=5|OwnerPartId=-1|Location.X=608|Location.Y=235|Color=8388608|FontID=1|IsHidden=T|Text=Datasheet|Name=ComponentLink2Description
|RECORD=41|OwnerIndex=983|IndexInSheet=6|OwnerPartId=-1|Location.X=608|Location.Y=235|Color=8388608|FontID=1|IsHidden=T|Text=Manufacturer URL|Name=ComponentLink1Description
|RECORD=41|OwnerIndex=983|IndexInSheet=7|OwnerPartId=-1|Location.X=608|Location.Y=235|Color=8388608|FontID=2|IsHidden=T|Text=https://datasheet.ciiva.com/11808/0900766b80f96399-11808223.pdf|Name=ComponentLink2URL
|RECORD=41|OwnerIndex=983|IndexInSheet=8|OwnerPartId=-1|Location.X=608|Location.Y=235|Color=8388608|FontID=1|IsHidden=T|Text=true|Name=RoHSCompliant
|RECORD=41|OwnerIndex=983|IndexInSheet=9|OwnerPartId=-1|Location.X=608|Location.Y=235|Color=8388608|FontID=1|IsHidden=T|Text=85 degC|Name=Max Operating Temperature
|RECORD=41|OwnerIndex=983|IndexInSheet=10|OwnerPartId=-1|Location.X=608|Location.Y=235|Color=8388608|FontID=1|IsHidden=T|Text=3.63 V|Name=Max Supply Voltage
|RECORD=41|OwnerIndex=983|IndexInSheet=11|OwnerPartId=-1|Location.X=608|Location.Y=235|Color=8388608|FontID=2|IsHidden=T|Text=http://www.yageo.com/|Name=ComponentLink1URL
|RECORD=41|OwnerIndex=983|IndexInSheet=12|OwnerPartId=-1|Location.X=608|Location.Y=235|Color=8388608|FontID=1|IsHidden=T|Text=2-Pin Surface Mount Device, Body 1.6 x 0.8 mm|Name=PackageDescription
|RECORD=41|OwnerIndex=983|IndexInSheet=13|OwnerPartId=-1|Location.X=608|Location.Y=235|Color=8388608|FontID=1|IsHidden=T|Text=LQFP|Name=Case\Package
|RECORD=41|OwnerIndex=983|IndexInSheet=14|OwnerPartId=-1|Location.X=608|Location.Y=235|Color=8388608|FontID=1|IsHidden=T|Text=Rev. 4, 04/2009|Name=DatasheetVersion
|RECORD=41|OwnerIndex=983|IndexInSheet=15|OwnerPartId=-1|Location.X=608|Location.Y=235|Color=8388608|FontID=1|IsHidden=T|Text=-40 degC|Name=Min Operating Temperature
|RECORD=41|OwnerIndex=983|IndexInSheet=16|OwnerPartId=-1|Location.X=608|Location.Y=235|Color=8388608|FontID=1|IsHidden=T|Text=SPI|Name=Interface
|RECORD=41|OwnerIndex=983|IndexInSheet=17|OwnerPartId=-1|Location.X=608|Location.Y=235|Color=8388608|FontID=1|IsHidden=T|Text=250|Name=Package Quantity
|RECORD=41|OwnerIndex=983|IndexInSheet=18|OwnerPartId=-1|Location.X=608|Location.Y=235|Color=8388608|FontID=1|IsHidden=T|Text=2.97 V|Name=Min Supply Voltage
|RECORD=41|OwnerIndex=983|IndexInSheet=19|OwnerPartId=-1|Location.X=608|Location.Y=235|Color=8388608|FontID=1|IsHidden=T|Text=48|Name=Pins
|RECORD=34|OwnerIndex=983|IndexInSheet=-1|OwnerPartId=-1|Location.X=619|Location.Y=223|Color=8388608|FontID=1|Text=R17|Name=Designator|ReadOnlyState=1
|RECORD=41|OwnerIndex=983|IndexInSheet=-1|OwnerPartId=-1|Location.X=619|Location.Y=207|Color=8388608|FontID=1|Text=49.9R|Name=Comment
|RECORD=44|OwnerIndex=983
|RECORD=45|OwnerIndex=1008|IndexInSheet=-1|Description=Chip Resistor, 2-Leads, Body 1.70x0.90mm, IPC Medium Density|UseComponentLibrary=T|ModelName=RESC1608X55X25NL10T15|ModelType=PCBLIB|DatafileCount=1|ModelDatafileEntity0=RESC1608X55X25NL10T15|ModelDatafileKind0=PCBLib|IsCurrent=T|DatalinksLocked=T|DatabaseDatalinksLocked=T
|RECORD=46|OwnerIndex=1009
|RECORD=48|OwnerIndex=1009
|RECORD=41|OwnerIndex=1011|IndexInSheet=-1|OwnerPartId=-1|Color=8388608|FontID=1|IsHidden=T|Text=2D|Name=Available Preview Images
|RECORD=45|OwnerIndex=1008|IndexInSheet=-1|Description=Chip Resistor, 2-Leads, Body 1.70x0.90mm, IPC Low Density|UseComponentLibrary=T|ModelName=RESC1608X55X25ML10T15|ModelType=PCBLIB|DatafileCount=1|ModelDatafileEntity0=RESC1608X55X25ML10T15|ModelDatafileKind0=PCBLib|DatalinksLocked=T|DatabaseDatalinksLocked=T
|RECORD=46|OwnerIndex=1013
|RECORD=48|OwnerIndex=1013
|RECORD=41|OwnerIndex=1015|IndexInSheet=-1|OwnerPartId=-1|Color=8388608|FontID=1|IsHidden=T|Text=2D|Name=Available Preview Images
|RECORD=45|OwnerIndex=1008|IndexInSheet=-1|Description=Chip Resistor, 2-Leads, Body 1.70x0.90mm, IPC High Density|UseComponentLibrary=T|ModelName=RESC1608X55X25LL10T15|ModelType=PCBLIB|DatafileCount=1|ModelDatafileEntity0=RESC1608X55X25LL10T15|ModelDatafileKind0=PCBLib|DatalinksLocked=T|DatabaseDatalinksLocked=T
|RECORD=46|OwnerIndex=1017
|RECORD=48|OwnerIndex=1017
|RECORD=41|OwnerIndex=1019|IndexInSheet=-1|OwnerPartId=-1|Color=8388608|FontID=1|IsHidden=T|Text=2D|Name=Available Preview Images
|RECORD=17|IndexInSheet=81|OwnerPartId=-1|Style=4|ShowNetName=T|Location.X=610|Location.Y=120|Orientation=3|Color=128|FontID=1|Text=GND
|RECORD=17|IndexInSheet=82|OwnerPartId=-1|Style=4|ShowNetName=T|Location.X=480|Location.Y=120|Orientation=3|Color=128|FontID=1|Text=GND
|RECORD=1|LibReference=CAP|ComponentDescription=C0603X104K5RACAUTO|PartCount=2|DisplayModeCount=2|IndexInSheet=83|OwnerPartId=-1|Location.X=440|Location.Y=170|Orientation=3|CurrentPartId=1|SourceLibraryName=Altium Content Vault|TargetFileName=*|AreaColor=11599871|Color=128|PartIDLocked=F|DesignItemId=CMP-2006-00003-1|AllPinCount=2
|RECORD=2|OwnerIndex=1023|OwnerPartId=1|OwnerPartDisplayMode=1|FormalType=1|Electrical=4|PinConglomerate=33|PinLength=10|Location.X=430|Location.Y=170|Name=1|Designator=1|PinPropagationDelay=0.000000E+000
|RECORD=2|OwnerIndex=1023|OwnerPartId=1|OwnerPartDisplayMode=1|FormalType=1|Electrical=4|PinConglomerate=35|PinLength=10|Location.X=430|Location.Y=160|Name=2|Designator=2|PinPropagationDelay=0.000000E+000
|RECORD=13|OwnerIndex=1023|IsNotAccesible=T|IndexInSheet=2|OwnerPartId=1|OwnerPartDisplayMode=1|Location.X=422|Location.Y=170|Corner.X=438|Corner.Y=170|LineWidth=1|Color=16711680
|RECORD=13|OwnerIndex=1023|IsNotAccesible=T|IndexInSheet=3|OwnerPartId=1|OwnerPartDisplayMode=1|Location.X=430|Location.Y=166|Corner.X=430|Corner.Y=160|LineWidth=1|Color=16711680
|RECORD=12|OwnerIndex=1023|IsNotAccesible=T|IndexInSheet=4|OwnerPartId=1|OwnerPartDisplayMode=1|Location.X=430|Location.Y=150|Radius=16|LineWidth=1|StartAngle=61.000|EndAngle=90.000|Color=16711680
|RECORD=12|OwnerIndex=1023|IsNotAccesible=T|IndexInSheet=5|OwnerPartId=1|OwnerPartDisplayMode=1|Location.X=430|Location.Y=150|Radius=16|LineWidth=1|StartAngle=90.000|EndAngle=119.000|Color=16711680
|RECORD=2|OwnerIndex=1023|OwnerPartId=1|FormalType=1|Electrical=4|PinConglomerate=33|PinLength=10|Location.X=430|Location.Y=170|Name=1|Designator=1|PinPropagationDelay=0.000000E+000
|RECORD=2|OwnerIndex=1023|OwnerPartId=1|FormalType=1|Electrical=4|PinConglomerate=35|PinLength=10|Location.X=430|Location.Y=160|Name=2|Designator=2|PinPropagationDelay=0.000000E+000
|RECORD=13|OwnerIndex=1023|IsNotAccesible=T|IndexInSheet=8|OwnerPartId=1|Location.X=438|Location.Y=163|Corner.X=422|Corner.Y=163|LineWidth=1|Color=16711680
|RECORD=13|OwnerIndex=1023|IsNotAccesible=T|IndexInSheet=9|OwnerPartId=1|Location.X=422|Location.Y=167|Corner.X=438|Corner.Y=167|LineWidth=1|Color=16711680
|RECORD=6|OwnerIndex=1023|IsNotAccesible=T|IndexInSheet=10|OwnerPartId=1|LineWidth=1|Color=16711680|LocationCount=2|X1=430|Y1=170|X2=430|Y2=167
|RECORD=6|OwnerIndex=1023|IsNotAccesible=T|IndexInSheet=11|OwnerPartId=1|LineWidth=1|Color=16711680|LocationCount=2|X1=430|Y1=160|X2=430|Y2=163
|RECORD=41|OwnerIndex=1023|IndexInSheet=12|OwnerPartId=-1|Location.X=421|Location.Y=182|Color=8388608|FontID=1|IsHidden=T|Text=Kemet|Name=Manufacturer
|RECORD=41|OwnerIndex=1023|IndexInSheet=13|OwnerPartId=-1|Location.X=421|Location.Y=182|Color=8388608|FontID=1|IsHidden=T|Text=C0603X104K5RACAUTO|Name=Part Number
|RECORD=34|OwnerIndex=1023|IndexInSheet=-1|OwnerPartId=-1|Location.X=439|Location.Y=157|Color=8388608|FontID=4|Text=C28|Name=Designator|ReadOnlyState=1
|RECORD=41|OwnerIndex=1023|IndexInSheet=-1|OwnerPartId=-1|Location.X=439|Location.Y=143|Color=8388608|FontID=4|Text=0.1uF|Name=Comment
|RECORD=44|OwnerIndex=1023
|RECORD=45|OwnerIndex=1044|IndexInSheet=-1|Description=Chip Capacitor, 2-Leads, Body 1.60x0.80mm, IPC Low Density|UseComponentLibrary=T|ModelName=CAPC1608X87X45ML20T05|ModelType=PCBLIB|DatafileCount=1|ModelDatafileEntity0=CAPC1608X87X45ML20T05|ModelDatafileKind0=PCBLib|IsCurrent=T|DatalinksLocked=T|DatabaseDatalinksLocked=T
|RECORD=46|OwnerIndex=1045
|RECORD=48|OwnerIndex=1045
|RECORD=41|OwnerIndex=1047|IndexInSheet=-1|OwnerPartId=-1|Color=8388608|FontID=1|Text=2D|Name=Available Preview Images
|RECORD=45|OwnerIndex=1044|IndexInSheet=-1|Description=Chip Capacitor, 2-Leads, Body 1.60x0.80mm, IPC High Density|UseComponentLibrary=T|ModelName=CAPC1608X87X45LL20T05|ModelType=PCBLIB|DatafileCount=1|ModelDatafileEntity0=CAPC1608X87X45LL20T05|ModelDatafileKind0=PCBLib|DatalinksLocked=T|DatabaseDatalinksLocked=T
|RECORD=46|OwnerIndex=1049
|RECORD=48|OwnerIndex=1049
|RECORD=41|OwnerIndex=1051|IndexInSheet=-1|OwnerPartId=-1|Color=8388608|FontID=1|Text=2D|Name=Available Preview Images
|RECORD=45|OwnerIndex=1044|IndexInSheet=-1|Description=Chip Capacitor, 2-Leads, Body 1.60x0.80mm, IPC Medium Density|UseComponentLibrary=T|ModelName=CAPC1608X87X45NL20T05|ModelType=PCBLIB|DatafileCount=1|ModelDatafileEntity0=CAPC1608X87X45NL20T05|ModelDatafileKind0=PCBLib|DatalinksLocked=T|DatabaseDatalinksLocked=T
|RECORD=46|OwnerIndex=1053
|RECORD=48|OwnerIndex=1053
|RECORD=41|OwnerIndex=1055|IndexInSheet=-1|OwnerPartId=-1|Color=8388608|FontID=1|Text=2D|Name=Available Preview Images
|RECORD=17|IndexInSheet=84|OwnerPartId=-1|Style=4|ShowNetName=T|Location.X=430|Location.Y=120|Orientation=3|Color=128|FontID=1|Text=GND
|RECORD=17|IndexInSheet=85|OwnerPartId=-1|ShowNetName=T|Location.X=430|Location.Y=300|Orientation=1|Color=128|FontID=1|Text=+3.3V
|RECORD=1|LibReference=3620477901728614f2110f3aa036e68|ComponentDescription=IC BUF NON-INVERT 5.5V SOT23-5|PartCount=2|DisplayModeCount=1|IndexInSheet=86|OwnerPartId=-1|Location.X=1120|Location.Y=610|IsMirrored=T|CurrentPartId=1|LibraryPath=*|SourceLibraryName=Altium Content Vault|TargetFileName=*|AreaColor=11599871|Color=128|PartIDLocked=T|DesignItemId=CMP-07111-000001-1|AllPinCount=5
|RECORD=14|OwnerIndex=1059|IsNotAccesible=T|OwnerPartId=1|Location.X=1060|Location.Y=540|Corner.X=1100|Corner.Y=620|LineWidth=1|Color=128|AreaColor=11599871|IsSolid=T
|RECORD=13|OwnerIndex=1059|IsNotAccesible=T|IndexInSheet=1|OwnerPartId=1|Location.X=1090|Location.Y=580|Corner.X=1090|Corner.Y=560|LineWidth=1|Color=16711680
|RECORD=13|OwnerIndex=1059|IsNotAccesible=T|IndexInSheet=2|OwnerPartId=1|Location.X=1090|Location.Y=560|Corner.X=1070|Corner.Y=570|LineWidth=1|Color=16711680
|RECORD=13|OwnerIndex=1059|IsNotAccesible=T|IndexInSheet=3|OwnerPartId=1|Location.X=1070|Location.Y=570|Corner.X=1090|Corner.Y=580|LineWidth=1|Color=16711680
|RECORD=13|OwnerIndex=1059|IsNotAccesible=T|IndexInSheet=4|OwnerPartId=1|Location.X=1090|Location.Y=580|Corner.X=1090|Corner.Y=570|LineWidth=1|Color=16711680
|RECORD=13|OwnerIndex=1059|IsNotAccesible=T|IndexInSheet=5|OwnerPartId=1|Location.X=1090|Location.Y=570|Corner.X=1100|Corner.Y=570|LineWidth=1|Color=16711680
|RECORD=13|OwnerIndex=1059|IsNotAccesible=T|IndexInSheet=6|OwnerPartId=1|Location.X=1070|Location.Y=570|Corner.X=1060|Corner.Y=570|LineWidth=1|Color=16711680
|RECORD=13|OwnerIndex=1059|IsNotAccesible=T|IndexInSheet=7|OwnerPartId=1|Location.X=1100|Location.Y=590|Corner.X=1080|Corner.Y=590|LineWidth=1|Color=16711680
|RECORD=13|OwnerIndex=1059|IsNotAccesible=T|IndexInSheet=8|OwnerPartId=1|Location.X=1080|Location.Y=590|Corner.X=1080|Corner.Y=580|LineWidth=1|Color=16711680
|RECORD=8|OwnerIndex=1059|IsNotAccesible=T|IndexInSheet=9|OwnerPartId=1|Location.X=1080|Location.Y=577|Radius=2|SecondaryRadius=2|LineWidth=1|Color=16711680
|RECORD=2|OwnerIndex=1059|OwnerPartId=1|PinConglomerate=48|PinLength=20|Location.X=1100|Location.Y=590|Name=O\E\|Designator=1|PinPropagationDelay=0.000000E+000
|RECORD=2|OwnerIndex=1059|OwnerPartId=1|PinConglomerate=48|PinLength=20|Location.X=1100|Location.Y=570|Name=A|Designator=2|PinPropagationDelay=0.000000E+000
|RECORD=2|OwnerIndex=1059|OwnerPartId=1|Electrical=7|PinConglomerate=58|PinLength=20|Location.X=1060|Location.Y=550|Name=GND|Designator=3|PinPropagationDelay=0.000000E+000
|RECORD=2|OwnerIndex=1059|OwnerPartId=1|Electrical=2|PinConglomerate=50|PinLength=20|Location.X=1060|Location.Y=570|Name=Y|Designator=4|PinPropagationDelay=0.000000E+000
|RECORD=2|OwnerIndex=1059|OwnerPartId=1|Electrical=7|PinConglomerate=56|PinLength=20|Location.X=1100|Location.Y=610|Name=VCC|Designator=5|PinPropagationDelay=0.000000E+000
|RECORD=41|OwnerIndex=1059|IndexInSheet=15|OwnerPartId=-1|Location.X=1038|Location.Y=620|Color=8388608|FontID=1|IsHidden=T|Text=+85°C|Name=Temperature Range High|IsMirrored=T
|RECORD=41|OwnerIndex=1059|IndexInSheet=16|OwnerPartId=-1|Location.X=1038|Location.Y=620|Color=8388608|FontID=1|IsHidden=T|Text=1|Name=Number Of Circuits|IsMirrored=T
|RECORD=41|OwnerIndex=1059|IndexInSheet=17|OwnerPartId=-1|Location.X=1038|Location.Y=620|Color=8388608|FontID=1|IsHidden=T|Text=1|Name=Number Of Outputs|IsMirrored=T
|RECORD=41|OwnerIndex=1059|IndexInSheet=18|OwnerPartId=-1|Location.X=1038|Location.Y=620|Color=8388608|FontID=1|IsHidden=T|Text=TRUE|Name=RoHS|IsMirrored=T
|RECORD=41|OwnerIndex=1059|IndexInSheet=19|OwnerPartId=-1|Location.X=1038|Location.Y=620|Color=8388608|FontID=1|IsHidden=T|Text=No|Name=Automotive|IsMirrored=T
|RECORD=41|OwnerIndex=1059|IndexInSheet=20|OwnerPartId=-1|Location.X=1038|Location.Y=620|Color=8388608|FontID=1|IsHidden=T|Text=IC|Name=Category|IsMirrored=T
|RECORD=41|OwnerIndex=1059|IndexInSheet=21|OwnerPartId=-1|Location.X=1038|Location.Y=620|Color=8388608|FontID=1|IsHidden=T|Text=+85°C|Name=Ambient Temperature Range High|IsMirrored=T
|RECORD=41|OwnerIndex=1059|IndexInSheet=22|OwnerPartId=-1|Location.X=1038|Location.Y=620|Color=8388608|FontID=1|IsHidden=T|Text=NC7SZ125M5|Name=Manufacturer Part Number|IsMirrored=T
|RECORD=41|OwnerIndex=1059|IndexInSheet=23|OwnerPartId=-1|Location.X=1038|Location.Y=620|Color=8388608|FontID=1|IsHidden=T|Text=Buffers|Name=Device Class L3|IsMirrored=T
|RECORD=41|OwnerIndex=1059|IndexInSheet=24|OwnerPartId=-1|Location.X=1038|Location.Y=620|Color=8388608|FontID=1|IsHidden=T|Text=ON Semiconductor|Name=Manufacturer|IsMirrored=T
|RECORD=41|OwnerIndex=1059|IndexInSheet=25|OwnerPartId=-1|Location.X=1038|Location.Y=620|Color=8388608|FontID=1|IsHidden=T|Text=-40°C|Name=Temperature Range Low|IsMirrored=T
|RECORD=41|OwnerIndex=1059|IndexInSheet=26|OwnerPartId=-1|Location.X=1038|Location.Y=620|Color=8388608|FontID=1|IsHidden=T|Text=+150°C|Name=Max Junction Temp|IsMirrored=T
|RECORD=41|OwnerIndex=1059|IndexInSheet=27|OwnerPartId=-1|Location.X=1038|Location.Y=620|Color=8388608|FontID=1|IsHidden=T|Text=Buffers & Line Drivers Buffer w/ 3-STAT O|Name=Mouser Description|IsMirrored=T
|RECORD=41|OwnerIndex=1059|IndexInSheet=28|OwnerPartId=-1|Location.X=1038|Location.Y=620|Color=8388608|FontID=1|IsHidden=T|Text=-40°C|Name=Ambient Temperature Range Low|IsMirrored=T
|RECORD=41|OwnerIndex=1059|IndexInSheet=29|OwnerPartId=-1|Location.X=1038|Location.Y=620|Color=8388608|FontID=1|IsHidden=T|Text=Yes|Name=Lead Free|IsMirrored=T
|RECORD=41|OwnerIndex=1059|IndexInSheet=30|OwnerPartId=-1|Location.X=1038|Location.Y=620|Color=8388608|FontID=1|IsHidden=T|Text=0.01mm|Name=Standoff Height|IsMirrored=T
|RECORD=41|OwnerIndex=1059|IndexInSheet=31|OwnerPartId=-1|Location.X=1038|Location.Y=620|Color=8388608|FontID=1|IsHidden=T|Text=SOT95P275X100-5|Name=Ipc Land Pattern Name|IsMirrored=T
|RECORD=41|OwnerIndex=1059|IndexInSheet=32|OwnerPartId=-1|Location.X=1038|Location.Y=620|Color=8388608|FontID=2|IsHidden=T|Text=https://www.onsemi.com/pub/Collateral/527AH.PDF|Name=Footprint Url|IsMirrored=T
|RECORD=41|OwnerIndex=1059|IndexInSheet=33|OwnerPartId=-1|Location.X=1038|Location.Y=620|Color=8388608|FontID=1|IsHidden=T|Text=Logic ICs|Name=Device Class L2|IsMirrored=T
|RECORD=41|OwnerIndex=1059|IndexInSheet=34|OwnerPartId=-1|Location.X=1038|Location.Y=620|Color=8388608|FontID=1|IsHidden=T|Text=5.5V|Name=Max Supply Voltage|IsMirrored=T
|RECORD=41|OwnerIndex=1059|IndexInSheet=35|OwnerPartId=-1|Location.X=1038|Location.Y=620|Color=8388608|FontID=1|IsHidden=T|Text=Non-Inverting|Name=Logic Function Desc|IsMirrored=T
|RECORD=41|OwnerIndex=1059|IndexInSheet=36|OwnerPartId=-1|Location.X=1038|Location.Y=620|Color=8388608|FontID=1|IsHidden=T|Text=2uA|Name=Nominal Supply Current|IsMirrored=T
|RECORD=41|OwnerIndex=1059|IndexInSheet=37|OwnerPartId=-1|Location.X=1038|Location.Y=620|Color=8388608|FontID=1|IsHidden=T|Text=2uA|Name=Quiescent Current|IsMirrored=T
|RECORD=41|OwnerIndex=1059|IndexInSheet=38|OwnerPartId=-1|Location.X=1038|Location.Y=620|Color=8388608|FontID=1|IsHidden=T|Text=1|Name=Number Of Inputs|IsMirrored=T
|RECORD=41|OwnerIndex=1059|IndexInSheet=39|OwnerPartId=-1|Location.X=1038|Location.Y=620|Color=8388608|FontID=1|IsHidden=T|Text=1.1mm|Name=Height|IsMirrored=T
|RECORD=41|OwnerIndex=1059|IndexInSheet=40|OwnerPartId=-1|Location.X=1038|Location.Y=620|Color=8388608|FontID=1|IsHidden=T|Text=-40°C to +85°C|Name=Temperature|IsMirrored=T
|RECORD=41|OwnerIndex=1059|IndexInSheet=41|OwnerPartId=-1|Location.X=1038|Location.Y=620|Color=8388608|FontID=1|IsHidden=T|Text=1.65V|Name=Min Supply Voltage|IsMirrored=T
|RECORD=41|OwnerIndex=1059|IndexInSheet=42|OwnerPartId=-1|Location.X=1038|Location.Y=620|Color=8388608|FontID=1|IsHidden=T|Text=Integrated Circuits (ICs)|Name=Device Class L1|IsMirrored=T
|RECORD=41|OwnerIndex=1059|IndexInSheet=43|OwnerPartId=-1|Location.X=1038|Location.Y=620|Color=8388608|FontID=1|IsHidden=T|Text=2.6ns|Name=Propagation Delay|IsMirrored=T
|RECORD=41|OwnerIndex=1059|IndexInSheet=44|OwnerPartId=-1|Location.X=1038|Location.Y=620|Color=8388608|FontID=2|IsHidden=T|Text=https://www.onsemi.com/pub/Collateral/NC7SZ125-D.PDF|Name=ComponentLink2URL|IsMirrored=T
|RECORD=41|OwnerIndex=1059|IndexInSheet=45|OwnerPartId=-1|Location.X=1038|Location.Y=620|Color=8388608|FontID=1|IsHidden=T|Text=IC BUF NON-INVERT 5.5V SOT23-5|Name=Digikey Description|IsMirrored=T
|RECORD=41|OwnerIndex=1059|IndexInSheet=46|OwnerPartId=-1|Location.X=1038|Location.Y=620|Color=8388608|FontID=1|IsHidden=T|Text=318BQ|Name=Package|IsMirrored=T
|RECORD=41|OwnerIndex=1059|IndexInSheet=47|OwnerPartId=-1|Location.X=1038|Location.Y=620|Color=8388608|FontID=2|IsHidden=T|Text=https://octopart.com/nc7sz125m5-on+semiconductor-84330746|Name=Octopart|IsMirrored=T
|RECORD=41|OwnerIndex=1059|IndexInSheet=48|OwnerPartId=-1|Location.X=1038|Location.Y=620|Color=8388608|FontID=1|IsHidden=T|Text=Datasheet|Name=ComponentLink2Description|IsMirrored=T
|RECORD=34|OwnerIndex=1059|IndexInSheet=-1|OwnerPartId=-1|Location.X=1059|Location.Y=620|Color=8388608|FontID=1|Text=U8|Name=Designator|ReadOnlyState=1|IsMirrored=T
|RECORD=41|OwnerIndex=1059|IndexInSheet=-1|OwnerPartId=1|Location.X=1059|Location.Y=530|Color=8388608|FontID=1|Text=NC7SZ125M5|Name=Comment|IsMirrored=T
|RECORD=44|OwnerIndex=1059
|RECORD=45|OwnerIndex=1116|IndexInSheet=-1|UseComponentLibrary=T|ModelName=FP-318BQ-MFG|ModelType=PCBLIB|DatafileCount=1|ModelDatafileEntity0=FP-318BQ-MFG|ModelDatafileKind0=PCBLib|IsCurrent=T|DatalinksLocked=T|DatabaseDatalinksLocked=T
|RECORD=46|OwnerIndex=1117
|RECORD=48|OwnerIndex=1117
|RECORD=45|OwnerIndex=1116|IndexInSheet=-1|UseComponentLibrary=T|ModelName=FP-318BQ-IPC_C|ModelType=PCBLIB|DatafileCount=1|ModelDatafileEntity0=FP-318BQ-IPC_C|ModelDatafileKind0=PCBLib|DatalinksLocked=T|DatabaseDatalinksLocked=T
|RECORD=46|OwnerIndex=1120
|RECORD=48|OwnerIndex=1120
|RECORD=45|OwnerIndex=1116|IndexInSheet=-1|UseComponentLibrary=T|ModelName=FP-318BQ-IPC_B|ModelType=PCBLIB|DatafileCount=1|ModelDatafileEntity0=FP-318BQ-IPC_B|ModelDatafileKind0=PCBLib|DatalinksLocked=T|DatabaseDatalinksLocked=T
|RECORD=46|OwnerIndex=1123
|RECORD=48|OwnerIndex=1123
|RECORD=45|OwnerIndex=1116|IndexInSheet=-1|UseComponentLibrary=T|ModelName=FP-318BQ-IPC_A|ModelType=PCBLIB|DatafileCount=1|ModelDatafileEntity0=FP-318BQ-IPC_A|ModelDatafileKind0=PCBLib|DatalinksLocked=T|DatabaseDatalinksLocked=T
|RECORD=46|OwnerIndex=1126
|RECORD=48|OwnerIndex=1126
|RECORD=1|LibReference=RES-2|ComponentDescription=General Purpose Chip Resistor, 49.9 Ohm, +/- 1%, -55 to 155 degC, 0603 (1608 Metric), RoHS, Tape and Reel|PartCount=2|DisplayModeCount=1|IndexInSheet=87|OwnerPartId=-1|Location.X=1210|Location.Y=570|CurrentPartId=1|LibraryPath=*|SourceLibraryName=Altium Content Vault|TargetFileName=*|AreaColor=11599871|Color=128|PartIDLocked=T|DesignItemId=CMP-1659-00036-1|AllPinCount=2
|RECORD=2|OwnerIndex=1129|OwnerPartId=1|FormalType=1|Electrical=4|PinConglomerate=32|PinLength=10|Location.X=1230|Location.Y=570|Name=2|Designator=2|PinPropagationDelay=0.000000E+000
|RECORD=2|OwnerIndex=1129|OwnerPartId=1|FormalType=1|Electrical=4|PinConglomerate=34|PinLength=10|Location.X=1210|Location.Y=570|Name=1|Designator=1|PinPropagationDelay=0.000000E+000
|RECORD=6|OwnerIndex=1129|IsNotAccesible=T|IndexInSheet=2|OwnerPartId=1|LineWidth=1|Color=16711680|LocationCount=10|X1=1230|Y1=570|X2=1226|Y2=570|X3=1225|Y3=568|X4=1223|Y4=572|X5=1221|Y5=568|X6=1219|Y6=572|X7=1217|Y7=568|X8=1215|Y8=572|X9=1214|Y9=570|X10=1210|Y10=570
|RECORD=41|OwnerIndex=1129|IndexInSheet=3|OwnerPartId=-1|Location.X=1198|Location.Y=585|Color=8388608|FontID=1|IsHidden=T|Text=0603|Name=PackageReference
|RECORD=41|OwnerIndex=1129|IndexInSheet=4|OwnerPartId=-1|Location.X=1198|Location.Y=585|Color=8388608|FontID=1|IsHidden=T|Text=Tray|Name=Packaging
|RECORD=41|OwnerIndex=1129|IndexInSheet=5|OwnerPartId=-1|Location.X=1198|Location.Y=585|Color=8388608|FontID=1|IsHidden=T|Text=Datasheet|Name=ComponentLink2Description
|RECORD=41|OwnerIndex=1129|IndexInSheet=6|OwnerPartId=-1|Location.X=1198|Location.Y=585|Color=8388608|FontID=1|IsHidden=T|Text=Manufacturer URL|Name=ComponentLink1Description
|RECORD=41|OwnerIndex=1129|IndexInSheet=7|OwnerPartId=-1|Location.X=1198|Location.Y=585|Color=8388608|FontID=2|IsHidden=T|Text=https://datasheet.ciiva.com/11808/0900766b80f96399-11808223.pdf|Name=ComponentLink2URL
|RECORD=41|OwnerIndex=1129|IndexInSheet=8|OwnerPartId=-1|Location.X=1198|Location.Y=585|Color=8388608|FontID=1|IsHidden=T|Text=true|Name=RoHSCompliant
|RECORD=41|OwnerIndex=1129|IndexInSheet=9|OwnerPartId=-1|Location.X=1198|Location.Y=585|Color=8388608|FontID=1|IsHidden=T|Text=85 degC|Name=Max Operating Temperature
|RECORD=41|OwnerIndex=1129|IndexInSheet=10|OwnerPartId=-1|Location.X=1198|Location.Y=585|Color=8388608|FontID=1|IsHidden=T|Text=3.63 V|Name=Max Supply Voltage
|RECORD=41|OwnerIndex=1129|IndexInSheet=11|OwnerPartId=-1|Location.X=1198|Location.Y=585|Color=8388608|FontID=2|IsHidden=T|Text=http://www.yageo.com/|Name=ComponentLink1URL
|RECORD=41|OwnerIndex=1129|IndexInSheet=12|OwnerPartId=-1|Location.X=1198|Location.Y=585|Color=8388608|FontID=1|IsHidden=T|Text=2-Pin Surface Mount Device, Body 1.6 x 0.8 mm|Name=PackageDescription
|RECORD=41|OwnerIndex=1129|IndexInSheet=13|OwnerPartId=-1|Location.X=1198|Location.Y=585|Color=8388608|FontID=1|IsHidden=T|Text=LQFP|Name=Case\Package
|RECORD=41|OwnerIndex=1129|IndexInSheet=14|OwnerPartId=-1|Location.X=1198|Location.Y=585|Color=8388608|FontID=1|IsHidden=T|Text=Rev. 4, 04/2009|Name=DatasheetVersion
|RECORD=41|OwnerIndex=1129|IndexInSheet=15|OwnerPartId=-1|Location.X=1198|Location.Y=585|Color=8388608|FontID=1|IsHidden=T|Text=-40 degC|Name=Min Operating Temperature
|RECORD=41|OwnerIndex=1129|IndexInSheet=16|OwnerPartId=-1|Location.X=1198|Location.Y=585|Color=8388608|FontID=1|IsHidden=T|Text=SPI|Name=Interface
|RECORD=41|OwnerIndex=1129|IndexInSheet=17|OwnerPartId=-1|Location.X=1198|Location.Y=585|Color=8388608|FontID=1|IsHidden=T|Text=250|Name=Package Quantity
|RECORD=41|OwnerIndex=1129|IndexInSheet=18|OwnerPartId=-1|Location.X=1198|Location.Y=585|Color=8388608|FontID=1|IsHidden=T|Text=2.97 V|Name=Min Supply Voltage
|RECORD=41|OwnerIndex=1129|IndexInSheet=19|OwnerPartId=-1|Location.X=1198|Location.Y=585|Color=8388608|FontID=1|IsHidden=T|Text=48|Name=Pins
|RECORD=34|OwnerIndex=1129|IndexInSheet=-1|OwnerPartId=-1|Location.X=1209|Location.Y=573|Color=8388608|FontID=1|Text=R15|Name=Designator|ReadOnlyState=1
|RECORD=41|OwnerIndex=1129|IndexInSheet=-1|OwnerPartId=-1|Location.X=1209|Location.Y=557|Color=8388608|FontID=1|Text=49.9R|Name=Comment
|RECORD=44|OwnerIndex=1129
|RECORD=45|OwnerIndex=1154|IndexInSheet=-1|Description=Chip Resistor, 2-Leads, Body 1.70x0.90mm, IPC Medium Density|UseComponentLibrary=T|ModelName=RESC1608X55X25NL10T15|ModelType=PCBLIB|DatafileCount=1|ModelDatafileEntity0=RESC1608X55X25NL10T15|ModelDatafileKind0=PCBLib|IsCurrent=T|DatalinksLocked=T|DatabaseDatalinksLocked=T
|RECORD=46|OwnerIndex=1155
|RECORD=48|OwnerIndex=1155
|RECORD=41|OwnerIndex=1157|IndexInSheet=-1|OwnerPartId=-1|Color=8388608|FontID=1|IsHidden=T|Text=2D|Name=Available Preview Images
|RECORD=45|OwnerIndex=1154|IndexInSheet=-1|Description=Chip Resistor, 2-Leads, Body 1.70x0.90mm, IPC Low Density|UseComponentLibrary=T|ModelName=RESC1608X55X25ML10T15|ModelType=PCBLIB|DatafileCount=1|ModelDatafileEntity0=RESC1608X55X25ML10T15|ModelDatafileKind0=PCBLib|DatalinksLocked=T|DatabaseDatalinksLocked=T
|RECORD=46|OwnerIndex=1159
|RECORD=48|OwnerIndex=1159
|RECORD=41|OwnerIndex=1161|IndexInSheet=-1|OwnerPartId=-1|Color=8388608|FontID=1|IsHidden=T|Text=2D|Name=Available Preview Images
|RECORD=45|OwnerIndex=1154|IndexInSheet=-1|Description=Chip Resistor, 2-Leads, Body 1.70x0.90mm, IPC High Density|UseComponentLibrary=T|ModelName=RESC1608X55X25LL10T15|ModelType=PCBLIB|DatafileCount=1|ModelDatafileEntity0=RESC1608X55X25LL10T15|ModelDatafileKind0=PCBLib|DatalinksLocked=T|DatabaseDatalinksLocked=T
|RECORD=46|OwnerIndex=1163
|RECORD=48|OwnerIndex=1163
|RECORD=41|OwnerIndex=1165|IndexInSheet=-1|OwnerPartId=-1|Color=8388608|FontID=1|IsHidden=T|Text=2D|Name=Available Preview Images
|RECORD=17|IndexInSheet=88|OwnerPartId=-1|Style=4|ShowNetName=T|Location.X=1190|Location.Y=470|Orientation=3|Color=128|FontID=1|Text=GND
|RECORD=17|IndexInSheet=89|OwnerPartId=-1|Style=4|ShowNetName=T|Location.X=1020|Location.Y=470|Orientation=3|Color=128|FontID=1|Text=GND
|RECORD=1|LibReference=CAP|ComponentDescription=C0603X104K5RACAUTO|PartCount=2|DisplayModeCount=2|IndexInSheet=90|OwnerPartId=-1|Location.X=1150|Location.Y=520|Orientation=3|CurrentPartId=1|SourceLibraryName=Altium Content Vault|TargetFileName=*|AreaColor=11599871|Color=128|PartIDLocked=F|DesignItemId=CMP-2006-00003-1|AllPinCount=2
|RECORD=2|OwnerIndex=1169|OwnerPartId=1|OwnerPartDisplayMode=1|FormalType=1|Electrical=4|PinConglomerate=33|PinLength=10|Location.X=1140|Location.Y=520|Name=1|Designator=1|PinPropagationDelay=0.000000E+000
|RECORD=2|OwnerIndex=1169|OwnerPartId=1|OwnerPartDisplayMode=1|FormalType=1|Electrical=4|PinConglomerate=35|PinLength=10|Location.X=1140|Location.Y=510|Name=2|Designator=2|PinPropagationDelay=0.000000E+000
|RECORD=13|OwnerIndex=1169|IsNotAccesible=T|IndexInSheet=2|OwnerPartId=1|OwnerPartDisplayMode=1|Location.X=1132|Location.Y=520|Corner.X=1148|Corner.Y=520|LineWidth=1|Color=16711680
|RECORD=13|OwnerIndex=1169|IsNotAccesible=T|IndexInSheet=3|OwnerPartId=1|OwnerPartDisplayMode=1|Location.X=1140|Location.Y=516|Corner.X=1140|Corner.Y=510|LineWidth=1|Color=16711680
|RECORD=12|OwnerIndex=1169|IsNotAccesible=T|IndexInSheet=4|OwnerPartId=1|OwnerPartDisplayMode=1|Location.X=1140|Location.Y=500|Radius=16|LineWidth=1|StartAngle=61.000|EndAngle=90.000|Color=16711680
|RECORD=12|OwnerIndex=1169|IsNotAccesible=T|IndexInSheet=5|OwnerPartId=1|OwnerPartDisplayMode=1|Location.X=1140|Location.Y=500|Radius=16|LineWidth=1|StartAngle=90.000|EndAngle=119.000|Color=16711680
|RECORD=2|OwnerIndex=1169|OwnerPartId=1|FormalType=1|Electrical=4|PinConglomerate=33|PinLength=10|Location.X=1140|Location.Y=520|Name=1|Designator=1|PinPropagationDelay=0.000000E+000
|RECORD=2|OwnerIndex=1169|OwnerPartId=1|FormalType=1|Electrical=4|PinConglomerate=35|PinLength=10|Location.X=1140|Location.Y=510|Name=2|Designator=2|PinPropagationDelay=0.000000E+000
|RECORD=13|OwnerIndex=1169|IsNotAccesible=T|IndexInSheet=8|OwnerPartId=1|Location.X=1148|Location.Y=513|Corner.X=1132|Corner.Y=513|LineWidth=1|Color=16711680
|RECORD=13|OwnerIndex=1169|IsNotAccesible=T|IndexInSheet=9|OwnerPartId=1|Location.X=1132|Location.Y=517|Corner.X=1148|Corner.Y=517|LineWidth=1|Color=16711680
|RECORD=6|OwnerIndex=1169|IsNotAccesible=T|IndexInSheet=10|OwnerPartId=1|LineWidth=1|Color=16711680|LocationCount=2|X1=1140|Y1=520|X2=1140|Y2=517
|RECORD=6|OwnerIndex=1169|IsNotAccesible=T|IndexInSheet=11|OwnerPartId=1|LineWidth=1|Color=16711680|LocationCount=2|X1=1140|Y1=510|X2=1140|Y2=513
|RECORD=41|OwnerIndex=1169|IndexInSheet=12|OwnerPartId=-1|Location.X=1131|Location.Y=532|Color=8388608|FontID=1|IsHidden=T|Text=Kemet|Name=Manufacturer
|RECORD=41|OwnerIndex=1169|IndexInSheet=13|OwnerPartId=-1|Location.X=1131|Location.Y=532|Color=8388608|FontID=1|IsHidden=T|Text=C0603X104K5RACAUTO|Name=Part Number
|RECORD=34|OwnerIndex=1169|IndexInSheet=-1|OwnerPartId=-1|Location.X=1149|Location.Y=507|Color=8388608|FontID=4|Text=C27|Name=Designator|ReadOnlyState=1
|RECORD=41|OwnerIndex=1169|IndexInSheet=-1|OwnerPartId=-1|Location.X=1149|Location.Y=493|Color=8388608|FontID=4|Text=0.1uF|Name=Comment
|RECORD=44|OwnerIndex=1169
|RECORD=45|OwnerIndex=1190|IndexInSheet=-1|Description=Chip Capacitor, 2-Leads, Body 1.60x0.80mm, IPC Low Density|UseComponentLibrary=T|ModelName=CAPC1608X87X45ML20T05|ModelType=PCBLIB|DatafileCount=1|ModelDatafileEntity0=CAPC1608X87X45ML20T05|ModelDatafileKind0=PCBLib|IsCurrent=T|DatalinksLocked=T|DatabaseDatalinksLocked=T
|RECORD=46|OwnerIndex=1191
|RECORD=48|OwnerIndex=1191
|RECORD=41|OwnerIndex=1193|IndexInSheet=-1|OwnerPartId=-1|Color=8388608|FontID=1|Text=2D|Name=Available Preview Images
|RECORD=45|OwnerIndex=1190|IndexInSheet=-1|Description=Chip Capacitor, 2-Leads, Body 1.60x0.80mm, IPC High Density|UseComponentLibrary=T|ModelName=CAPC1608X87X45LL20T05|ModelType=PCBLIB|DatafileCount=1|ModelDatafileEntity0=CAPC1608X87X45LL20T05|ModelDatafileKind0=PCBLib|DatalinksLocked=T|DatabaseDatalinksLocked=T
|RECORD=46|OwnerIndex=1195
|RECORD=48|OwnerIndex=1195
|RECORD=41|OwnerIndex=1197|IndexInSheet=-1|OwnerPartId=-1|Color=8388608|FontID=1|Text=2D|Name=Available Preview Images
|RECORD=45|OwnerIndex=1190|IndexInSheet=-1|Description=Chip Capacitor, 2-Leads, Body 1.60x0.80mm, IPC Medium Density|UseComponentLibrary=T|ModelName=CAPC1608X87X45NL20T05|ModelType=PCBLIB|DatafileCount=1|ModelDatafileEntity0=CAPC1608X87X45NL20T05|ModelDatafileKind0=PCBLib|DatalinksLocked=T|DatabaseDatalinksLocked=T
|RECORD=46|OwnerIndex=1199
|RECORD=48|OwnerIndex=1199
|RECORD=41|OwnerIndex=1201|IndexInSheet=-1|OwnerPartId=-1|Color=8388608|FontID=1|Text=2D|Name=Available Preview Images
|RECORD=17|IndexInSheet=91|OwnerPartId=-1|Style=4|ShowNetName=T|Location.X=1140|Location.Y=470|Orientation=3|Color=128|FontID=1|Text=GND
|RECORD=17|IndexInSheet=92|OwnerPartId=-1|ShowNetName=T|Location.X=1140|Location.Y=650|Orientation=1|Color=128|FontID=1|Text=+3.3V
|RECORD=1|LibReference=3620477901728614f2110f3aa036e68|ComponentDescription=IC BUF NON-INVERT 5.5V SOT23-5|PartCount=2|DisplayModeCount=1|IndexInSheet=93|OwnerPartId=-1|Location.X=1120|Location.Y=290|IsMirrored=T|CurrentPartId=1|LibraryPath=*|SourceLibraryName=Altium Content Vault|TargetFileName=*|AreaColor=11599871|Color=128|PartIDLocked=T|DesignItemId=CMP-07111-000001-1|AllPinCount=5
|RECORD=14|OwnerIndex=1205|IsNotAccesible=T|OwnerPartId=1|Location.X=1060|Location.Y=220|Corner.X=1100|Corner.Y=300|LineWidth=1|Color=128|AreaColor=11599871|IsSolid=T
|RECORD=13|OwnerIndex=1205|IsNotAccesible=T|IndexInSheet=1|OwnerPartId=1|Location.X=1090|Location.Y=260|Corner.X=1090|Corner.Y=240|LineWidth=1|Color=16711680
|RECORD=13|OwnerIndex=1205|IsNotAccesible=T|IndexInSheet=2|OwnerPartId=1|Location.X=1090|Location.Y=240|Corner.X=1070|Corner.Y=250|LineWidth=1|Color=16711680
|RECORD=13|OwnerIndex=1205|IsNotAccesible=T|IndexInSheet=3|OwnerPartId=1|Location.X=1070|Location.Y=250|Corner.X=1090|Corner.Y=260|LineWidth=1|Color=16711680
|RECORD=13|OwnerIndex=1205|IsNotAccesible=T|IndexInSheet=4|OwnerPartId=1|Location.X=1090|Location.Y=260|Corner.X=1090|Corner.Y=250|LineWidth=1|Color=16711680
|RECORD=13|OwnerIndex=1205|IsNotAccesible=T|IndexInSheet=5|OwnerPartId=1|Location.X=1090|Location.Y=250|Corner.X=1100|Corner.Y=250|LineWidth=1|Color=16711680
|RECORD=13|OwnerIndex=1205|IsNotAccesible=T|IndexInSheet=6|OwnerPartId=1|Location.X=1070|Location.Y=250|Corner.X=1060|Corner.Y=250|LineWidth=1|Color=16711680
|RECORD=13|OwnerIndex=1205|IsNotAccesible=T|IndexInSheet=7|OwnerPartId=1|Location.X=1100|Location.Y=270|Corner.X=1080|Corner.Y=270|LineWidth=1|Color=16711680
|RECORD=13|OwnerIndex=1205|IsNotAccesible=T|IndexInSheet=8|OwnerPartId=1|Location.X=1080|Location.Y=270|Corner.X=1080|Corner.Y=260|LineWidth=1|Color=16711680
|RECORD=8|OwnerIndex=1205|IsNotAccesible=T|IndexInSheet=9|OwnerPartId=1|Location.X=1080|Location.Y=257|Radius=2|SecondaryRadius=2|LineWidth=1|Color=16711680
|RECORD=2|OwnerIndex=1205|OwnerPartId=1|PinConglomerate=48|PinLength=20|Location.X=1100|Location.Y=270|Name=O\E\|Designator=1|PinPropagationDelay=0.000000E+000
|RECORD=2|OwnerIndex=1205|OwnerPartId=1|PinConglomerate=48|PinLength=20|Location.X=1100|Location.Y=250|Name=A|Designator=2|PinPropagationDelay=0.000000E+000
|RECORD=2|OwnerIndex=1205|OwnerPartId=1|Electrical=7|PinConglomerate=58|PinLength=20|Location.X=1060|Location.Y=230|Name=GND|Designator=3|PinPropagationDelay=0.000000E+000
|RECORD=2|OwnerIndex=1205|OwnerPartId=1|Electrical=2|PinConglomerate=50|PinLength=20|Location.X=1060|Location.Y=250|Name=Y|Designator=4|PinPropagationDelay=0.000000E+000
|RECORD=2|OwnerIndex=1205|OwnerPartId=1|Electrical=7|PinConglomerate=56|PinLength=20|Location.X=1100|Location.Y=290|Name=VCC|Designator=5|PinPropagationDelay=0.000000E+000
|RECORD=41|OwnerIndex=1205|IndexInSheet=15|OwnerPartId=-1|Location.X=1038|Location.Y=300|Color=8388608|FontID=1|IsHidden=T|Text=+85°C|Name=Temperature Range High|IsMirrored=T
|RECORD=41|OwnerIndex=1205|IndexInSheet=16|OwnerPartId=-1|Location.X=1038|Location.Y=300|Color=8388608|FontID=1|IsHidden=T|Text=1|Name=Number Of Circuits|IsMirrored=T
|RECORD=41|OwnerIndex=1205|IndexInSheet=17|OwnerPartId=-1|Location.X=1038|Location.Y=300|Color=8388608|FontID=1|IsHidden=T|Text=1|Name=Number Of Outputs|IsMirrored=T
|RECORD=41|OwnerIndex=1205|IndexInSheet=18|OwnerPartId=-1|Location.X=1038|Location.Y=300|Color=8388608|FontID=1|IsHidden=T|Text=TRUE|Name=RoHS|IsMirrored=T
|RECORD=41|OwnerIndex=1205|IndexInSheet=19|OwnerPartId=-1|Location.X=1038|Location.Y=300|Color=8388608|FontID=1|IsHidden=T|Text=No|Name=Automotive|IsMirrored=T
|RECORD=41|OwnerIndex=1205|IndexInSheet=20|OwnerPartId=-1|Location.X=1038|Location.Y=300|Color=8388608|FontID=1|IsHidden=T|Text=IC|Name=Category|IsMirrored=T
|RECORD=41|OwnerIndex=1205|IndexInSheet=21|OwnerPartId=-1|Location.X=1038|Location.Y=300|Color=8388608|FontID=1|IsHidden=T|Text=+85°C|Name=Ambient Temperature Range High|IsMirrored=T
|RECORD=41|OwnerIndex=1205|IndexInSheet=22|OwnerPartId=-1|Location.X=1038|Location.Y=300|Color=8388608|FontID=1|IsHidden=T|Text=NC7SZ125M5|Name=Manufacturer Part Number|IsMirrored=T
|RECORD=41|OwnerIndex=1205|IndexInSheet=23|OwnerPartId=-1|Location.X=1038|Location.Y=300|Color=8388608|FontID=1|IsHidden=T|Text=Buffers|Name=Device Class L3|IsMirrored=T
|RECORD=41|OwnerIndex=1205|IndexInSheet=24|OwnerPartId=-1|Location.X=1038|Location.Y=300|Color=8388608|FontID=1|IsHidden=T|Text=ON Semiconductor|Name=Manufacturer|IsMirrored=T
|RECORD=41|OwnerIndex=1205|IndexInSheet=25|OwnerPartId=-1|Location.X=1038|Location.Y=300|Color=8388608|FontID=1|IsHidden=T|Text=-40°C|Name=Temperature Range Low|IsMirrored=T
|RECORD=41|OwnerIndex=1205|IndexInSheet=26|OwnerPartId=-1|Location.X=1038|Location.Y=300|Color=8388608|FontID=1|IsHidden=T|Text=+150°C|Name=Max Junction Temp|IsMirrored=T
|RECORD=41|OwnerIndex=1205|IndexInSheet=27|OwnerPartId=-1|Location.X=1038|Location.Y=300|Color=8388608|FontID=1|IsHidden=T|Text=Buffers & Line Drivers Buffer w/ 3-STAT O|Name=Mouser Description|IsMirrored=T
|RECORD=41|OwnerIndex=1205|IndexInSheet=28|OwnerPartId=-1|Location.X=1038|Location.Y=300|Color=8388608|FontID=1|IsHidden=T|Text=-40°C|Name=Ambient Temperature Range Low|IsMirrored=T
|RECORD=41|OwnerIndex=1205|IndexInSheet=29|OwnerPartId=-1|Location.X=1038|Location.Y=300|Color=8388608|FontID=1|IsHidden=T|Text=Yes|Name=Lead Free|IsMirrored=T
|RECORD=41|OwnerIndex=1205|IndexInSheet=30|OwnerPartId=-1|Location.X=1038|Location.Y=300|Color=8388608|FontID=1|IsHidden=T|Text=0.01mm|Name=Standoff Height|IsMirrored=T
|RECORD=41|OwnerIndex=1205|IndexInSheet=31|OwnerPartId=-1|Location.X=1038|Location.Y=300|Color=8388608|FontID=1|IsHidden=T|Text=SOT95P275X100-5|Name=Ipc Land Pattern Name|IsMirrored=T
|RECORD=41|OwnerIndex=1205|IndexInSheet=32|OwnerPartId=-1|Location.X=1038|Location.Y=300|Color=8388608|FontID=2|IsHidden=T|Text=https://www.onsemi.com/pub/Collateral/527AH.PDF|Name=Footprint Url|IsMirrored=T
|RECORD=41|OwnerIndex=1205|IndexInSheet=33|OwnerPartId=-1|Location.X=1038|Location.Y=300|Color=8388608|FontID=1|IsHidden=T|Text=Logic ICs|Name=Device Class L2|IsMirrored=T
|RECORD=41|OwnerIndex=1205|IndexInSheet=34|OwnerPartId=-1|Location.X=1038|Location.Y=300|Color=8388608|FontID=1|IsHidden=T|Text=5.5V|Name=Max Supply Voltage|IsMirrored=T
|RECORD=41|OwnerIndex=1205|IndexInSheet=35|OwnerPartId=-1|Location.X=1038|Location.Y=300|Color=8388608|FontID=1|IsHidden=T|Text=Non-Inverting|Name=Logic Function Desc|IsMirrored=T
|RECORD=41|OwnerIndex=1205|IndexInSheet=36|OwnerPartId=-1|Location.X=1038|Location.Y=300|Color=8388608|FontID=1|IsHidden=T|Text=2uA|Name=Nominal Supply Current|IsMirrored=T
|RECORD=41|OwnerIndex=1205|IndexInSheet=37|OwnerPartId=-1|Location.X=1038|Location.Y=300|Color=8388608|FontID=1|IsHidden=T|Text=2uA|Name=Quiescent Current|IsMirrored=T
|RECORD=41|OwnerIndex=1205|IndexInSheet=38|OwnerPartId=-1|Location.X=1038|Location.Y=300|Color=8388608|FontID=1|IsHidden=T|Text=1|Name=Number Of Inputs|IsMirrored=T
|RECORD=41|OwnerIndex=1205|IndexInSheet=39|OwnerPartId=-1|Location.X=1038|Location.Y=300|Color=8388608|FontID=1|IsHidden=T|Text=1.1mm|Name=Height|IsMirrored=T
|RECORD=41|OwnerIndex=1205|IndexInSheet=40|OwnerPartId=-1|Location.X=1038|Location.Y=300|Color=8388608|FontID=1|IsHidden=T|Text=-40°C to +85°C|Name=Temperature|IsMirrored=T
|RECORD=41|OwnerIndex=1205|IndexInSheet=41|OwnerPartId=-1|Location.X=1038|Location.Y=300|Color=8388608|FontID=1|IsHidden=T|Text=1.65V|Name=Min Supply Voltage|IsMirrored=T
|RECORD=41|OwnerIndex=1205|IndexInSheet=42|OwnerPartId=-1|Location.X=1038|Location.Y=300|Color=8388608|FontID=1|IsHidden=T|Text=Integrated Circuits (ICs)|Name=Device Class L1|IsMirrored=T
|RECORD=41|OwnerIndex=1205|IndexInSheet=43|OwnerPartId=-1|Location.X=1038|Location.Y=300|Color=8388608|FontID=1|IsHidden=T|Text=2.6ns|Name=Propagation Delay|IsMirrored=T
|RECORD=41|OwnerIndex=1205|IndexInSheet=44|OwnerPartId=-1|Location.X=1038|Location.Y=300|Color=8388608|FontID=2|IsHidden=T|Text=https://www.onsemi.com/pub/Collateral/NC7SZ125-D.PDF|Name=ComponentLink2URL|IsMirrored=T
|RECORD=41|OwnerIndex=1205|IndexInSheet=45|OwnerPartId=-1|Location.X=1038|Location.Y=300|Color=8388608|FontID=1|IsHidden=T|Text=IC BUF NON-INVERT 5.5V SOT23-5|Name=Digikey Description|IsMirrored=T
|RECORD=41|OwnerIndex=1205|IndexInSheet=46|OwnerPartId=-1|Location.X=1038|Location.Y=300|Color=8388608|FontID=1|IsHidden=T|Text=318BQ|Name=Package|IsMirrored=T
|RECORD=41|OwnerIndex=1205|IndexInSheet=47|OwnerPartId=-1|Location.X=1038|Location.Y=300|Color=8388608|FontID=2|IsHidden=T|Text=https://octopart.com/nc7sz125m5-on+semiconductor-84330746|Name=Octopart|IsMirrored=T
|RECORD=41|OwnerIndex=1205|IndexInSheet=48|OwnerPartId=-1|Location.X=1038|Location.Y=300|Color=8388608|FontID=1|IsHidden=T|Text=Datasheet|Name=ComponentLink2Description|IsMirrored=T
|RECORD=34|OwnerIndex=1205|IndexInSheet=-1|OwnerPartId=-1|Location.X=1059|Location.Y=300|Color=8388608|FontID=1|Text=U12|Name=Designator|ReadOnlyState=1|IsMirrored=T
|RECORD=41|OwnerIndex=1205|IndexInSheet=-1|OwnerPartId=1|Location.X=1059|Location.Y=210|Color=8388608|FontID=1|Text=NC7SZ125M5|Name=Comment|IsMirrored=T
|RECORD=44|OwnerIndex=1205
|RECORD=45|OwnerIndex=1262|IndexInSheet=-1|UseComponentLibrary=T|ModelName=FP-318BQ-MFG|ModelType=PCBLIB|DatafileCount=1|ModelDatafileEntity0=FP-318BQ-MFG|ModelDatafileKind0=PCBLib|IsCurrent=T|DatalinksLocked=T|DatabaseDatalinksLocked=T
|RECORD=46|OwnerIndex=1263
|RECORD=48|OwnerIndex=1263
|RECORD=45|OwnerIndex=1262|IndexInSheet=-1|UseComponentLibrary=T|ModelName=FP-318BQ-IPC_C|ModelType=PCBLIB|DatafileCount=1|ModelDatafileEntity0=FP-318BQ-IPC_C|ModelDatafileKind0=PCBLib|DatalinksLocked=T|DatabaseDatalinksLocked=T
|RECORD=46|OwnerIndex=1266
|RECORD=48|OwnerIndex=1266
|RECORD=45|OwnerIndex=1262|IndexInSheet=-1|UseComponentLibrary=T|ModelName=FP-318BQ-IPC_B|ModelType=PCBLIB|DatafileCount=1|ModelDatafileEntity0=FP-318BQ-IPC_B|ModelDatafileKind0=PCBLib|DatalinksLocked=T|DatabaseDatalinksLocked=T
|RECORD=46|OwnerIndex=1269
|RECORD=48|OwnerIndex=1269
|RECORD=45|OwnerIndex=1262|IndexInSheet=-1|UseComponentLibrary=T|ModelName=FP-318BQ-IPC_A|ModelType=PCBLIB|DatafileCount=1|ModelDatafileEntity0=FP-318BQ-IPC_A|ModelDatafileKind0=PCBLib|DatalinksLocked=T|DatabaseDatalinksLocked=T
|RECORD=46|OwnerIndex=1272
|RECORD=48|OwnerIndex=1272
|RECORD=1|LibReference=RES-2|ComponentDescription=General Purpose Chip Resistor, 49.9 Ohm, +/- 1%, -55 to 155 degC, 0603 (1608 Metric), RoHS, Tape and Reel|PartCount=2|DisplayModeCount=1|IndexInSheet=94|OwnerPartId=-1|Location.X=1210|Location.Y=250|CurrentPartId=1|LibraryPath=*|SourceLibraryName=Altium Content Vault|TargetFileName=*|AreaColor=11599871|Color=128|PartIDLocked=T|DesignItemId=CMP-1659-00036-1|AllPinCount=2
|RECORD=2|OwnerIndex=1275|OwnerPartId=1|FormalType=1|Electrical=4|PinConglomerate=32|PinLength=10|Location.X=1230|Location.Y=250|Name=2|Designator=2|PinPropagationDelay=0.000000E+000
|RECORD=2|OwnerIndex=1275|OwnerPartId=1|FormalType=1|Electrical=4|PinConglomerate=34|PinLength=10|Location.X=1210|Location.Y=250|Name=1|Designator=1|PinPropagationDelay=0.000000E+000
|RECORD=6|OwnerIndex=1275|IsNotAccesible=T|IndexInSheet=2|OwnerPartId=1|LineWidth=1|Color=16711680|LocationCount=10|X1=1230|Y1=250|X2=1226|Y2=250|X3=1225|Y3=248|X4=1223|Y4=252|X5=1221|Y5=248|X6=1219|Y6=252|X7=1217|Y7=248|X8=1215|Y8=252|X9=1214|Y9=250|X10=1210|Y10=250
|RECORD=41|OwnerIndex=1275|IndexInSheet=3|OwnerPartId=-1|Location.X=1198|Location.Y=265|Color=8388608|FontID=1|IsHidden=T|Text=0603|Name=PackageReference
|RECORD=41|OwnerIndex=1275|IndexInSheet=4|OwnerPartId=-1|Location.X=1198|Location.Y=265|Color=8388608|FontID=1|IsHidden=T|Text=Tray|Name=Packaging
|RECORD=41|OwnerIndex=1275|IndexInSheet=5|OwnerPartId=-1|Location.X=1198|Location.Y=265|Color=8388608|FontID=1|IsHidden=T|Text=Datasheet|Name=ComponentLink2Description
|RECORD=41|OwnerIndex=1275|IndexInSheet=6|OwnerPartId=-1|Location.X=1198|Location.Y=265|Color=8388608|FontID=1|IsHidden=T|Text=Manufacturer URL|Name=ComponentLink1Description
|RECORD=41|OwnerIndex=1275|IndexInSheet=7|OwnerPartId=-1|Location.X=1198|Location.Y=265|Color=8388608|FontID=2|IsHidden=T|Text=https://datasheet.ciiva.com/11808/0900766b80f96399-11808223.pdf|Name=ComponentLink2URL
|RECORD=41|OwnerIndex=1275|IndexInSheet=8|OwnerPartId=-1|Location.X=1198|Location.Y=265|Color=8388608|FontID=1|IsHidden=T|Text=true|Name=RoHSCompliant
|RECORD=41|OwnerIndex=1275|IndexInSheet=9|OwnerPartId=-1|Location.X=1198|Location.Y=265|Color=8388608|FontID=1|IsHidden=T|Text=85 degC|Name=Max Operating Temperature
|RECORD=41|OwnerIndex=1275|IndexInSheet=10|OwnerPartId=-1|Location.X=1198|Location.Y=265|Color=8388608|FontID=1|IsHidden=T|Text=3.63 V|Name=Max Supply Voltage
|RECORD=41|OwnerIndex=1275|IndexInSheet=11|OwnerPartId=-1|Location.X=1198|Location.Y=265|Color=8388608|FontID=2|IsHidden=T|Text=http://www.yageo.com/|Name=ComponentLink1URL
|RECORD=41|OwnerIndex=1275|IndexInSheet=12|OwnerPartId=-1|Location.X=1198|Location.Y=265|Color=8388608|FontID=1|IsHidden=T|Text=2-Pin Surface Mount Device, Body 1.6 x 0.8 mm|Name=PackageDescription
|RECORD=41|OwnerIndex=1275|IndexInSheet=13|OwnerPartId=-1|Location.X=1198|Location.Y=265|Color=8388608|FontID=1|IsHidden=T|Text=LQFP|Name=Case\Package
|RECORD=41|OwnerIndex=1275|IndexInSheet=14|OwnerPartId=-1|Location.X=1198|Location.Y=265|Color=8388608|FontID=1|IsHidden=T|Text=Rev. 4, 04/2009|Name=DatasheetVersion
|RECORD=41|OwnerIndex=1275|IndexInSheet=15|OwnerPartId=-1|Location.X=1198|Location.Y=265|Color=8388608|FontID=1|IsHidden=T|Text=-40 degC|Name=Min Operating Temperature
|RECORD=41|OwnerIndex=1275|IndexInSheet=16|OwnerPartId=-1|Location.X=1198|Location.Y=265|Color=8388608|FontID=1|IsHidden=T|Text=SPI|Name=Interface
|RECORD=41|OwnerIndex=1275|IndexInSheet=17|OwnerPartId=-1|Location.X=1198|Location.Y=265|Color=8388608|FontID=1|IsHidden=T|Text=250|Name=Package Quantity
|RECORD=41|OwnerIndex=1275|IndexInSheet=18|OwnerPartId=-1|Location.X=1198|Location.Y=265|Color=8388608|FontID=1|IsHidden=T|Text=2.97 V|Name=Min Supply Voltage
|RECORD=41|OwnerIndex=1275|IndexInSheet=19|OwnerPartId=-1|Location.X=1198|Location.Y=265|Color=8388608|FontID=1|IsHidden=T|Text=48|Name=Pins
|RECORD=34|OwnerIndex=1275|IndexInSheet=-1|OwnerPartId=-1|Location.X=1209|Location.Y=253|Color=8388608|FontID=1|Text=R25|Name=Designator|ReadOnlyState=1
|RECORD=41|OwnerIndex=1275|IndexInSheet=-1|OwnerPartId=-1|Location.X=1209|Location.Y=237|Color=8388608|FontID=1|Text=49.9R|Name=Comment
|RECORD=44|OwnerIndex=1275
|RECORD=45|OwnerIndex=1300|IndexInSheet=-1|Description=Chip Resistor, 2-Leads, Body 1.70x0.90mm, IPC Medium Density|UseComponentLibrary=T|ModelName=RESC1608X55X25NL10T15|ModelType=PCBLIB|DatafileCount=1|ModelDatafileEntity0=RESC1608X55X25NL10T15|ModelDatafileKind0=PCBLib|IsCurrent=T|DatalinksLocked=T|DatabaseDatalinksLocked=T
|RECORD=46|OwnerIndex=1301
|RECORD=48|OwnerIndex=1301
|RECORD=41|OwnerIndex=1303|IndexInSheet=-1|OwnerPartId=-1|Color=8388608|FontID=1|IsHidden=T|Text=2D|Name=Available Preview Images
|RECORD=45|OwnerIndex=1300|IndexInSheet=-1|Description=Chip Resistor, 2-Leads, Body 1.70x0.90mm, IPC Low Density|UseComponentLibrary=T|ModelName=RESC1608X55X25ML10T15|ModelType=PCBLIB|DatafileCount=1|ModelDatafileEntity0=RESC1608X55X25ML10T15|ModelDatafileKind0=PCBLib|DatalinksLocked=T|DatabaseDatalinksLocked=T
|RECORD=46|OwnerIndex=1305
|RECORD=48|OwnerIndex=1305
|RECORD=41|OwnerIndex=1307|IndexInSheet=-1|OwnerPartId=-1|Color=8388608|FontID=1|IsHidden=T|Text=2D|Name=Available Preview Images
|RECORD=45|OwnerIndex=1300|IndexInSheet=-1|Description=Chip Resistor, 2-Leads, Body 1.70x0.90mm, IPC High Density|UseComponentLibrary=T|ModelName=RESC1608X55X25LL10T15|ModelType=PCBLIB|DatafileCount=1|ModelDatafileEntity0=RESC1608X55X25LL10T15|ModelDatafileKind0=PCBLib|DatalinksLocked=T|DatabaseDatalinksLocked=T
|RECORD=46|OwnerIndex=1309
|RECORD=48|OwnerIndex=1309
|RECORD=41|OwnerIndex=1311|IndexInSheet=-1|OwnerPartId=-1|Color=8388608|FontID=1|IsHidden=T|Text=2D|Name=Available Preview Images
|RECORD=17|IndexInSheet=95|OwnerPartId=-1|Style=4|ShowNetName=T|Location.X=1190|Location.Y=150|Orientation=3|Color=128|FontID=1|Text=GND
|RECORD=17|IndexInSheet=96|OwnerPartId=-1|Style=4|ShowNetName=T|Location.X=1140|Location.Y=150|Orientation=3|Color=128|FontID=1|Text=GND
|RECORD=1|LibReference=CAP|ComponentDescription=C0603X104K5RACAUTO|PartCount=2|DisplayModeCount=2|IndexInSheet=97|OwnerPartId=-1|Location.X=1150|Location.Y=200|Orientation=3|CurrentPartId=1|SourceLibraryName=Altium Content Vault|TargetFileName=*|AreaColor=11599871|Color=128|PartIDLocked=F|DesignItemId=CMP-2006-00003-1|AllPinCount=2
|RECORD=2|OwnerIndex=1315|OwnerPartId=1|OwnerPartDisplayMode=1|FormalType=1|Electrical=4|PinConglomerate=33|PinLength=10|Location.X=1140|Location.Y=200|Name=1|Designator=1|PinPropagationDelay=0.000000E+000
|RECORD=2|OwnerIndex=1315|OwnerPartId=1|OwnerPartDisplayMode=1|FormalType=1|Electrical=4|PinConglomerate=35|PinLength=10|Location.X=1140|Location.Y=190|Name=2|Designator=2|PinPropagationDelay=0.000000E+000
|RECORD=13|OwnerIndex=1315|IsNotAccesible=T|IndexInSheet=2|OwnerPartId=1|OwnerPartDisplayMode=1|Location.X=1132|Location.Y=200|Corner.X=1148|Corner.Y=200|LineWidth=1|Color=16711680
|RECORD=13|OwnerIndex=1315|IsNotAccesible=T|IndexInSheet=3|OwnerPartId=1|OwnerPartDisplayMode=1|Location.X=1140|Location.Y=196|Corner.X=1140|Corner.Y=190|LineWidth=1|Color=16711680
|RECORD=12|OwnerIndex=1315|IsNotAccesible=T|IndexInSheet=4|OwnerPartId=1|OwnerPartDisplayMode=1|Location.X=1140|Location.Y=180|Radius=16|LineWidth=1|StartAngle=61.000|EndAngle=90.000|Color=16711680
|RECORD=12|OwnerIndex=1315|IsNotAccesible=T|IndexInSheet=5|OwnerPartId=1|OwnerPartDisplayMode=1|Location.X=1140|Location.Y=180|Radius=16|LineWidth=1|StartAngle=90.000|EndAngle=119.000|Color=16711680
|RECORD=2|OwnerIndex=1315|OwnerPartId=1|FormalType=1|Electrical=4|PinConglomerate=33|PinLength=10|Location.X=1140|Location.Y=200|Name=1|Designator=1|PinPropagationDelay=0.000000E+000
|RECORD=2|OwnerIndex=1315|OwnerPartId=1|FormalType=1|Electrical=4|PinConglomerate=35|PinLength=10|Location.X=1140|Location.Y=190|Name=2|Designator=2|PinPropagationDelay=0.000000E+000
|RECORD=13|OwnerIndex=1315|IsNotAccesible=T|IndexInSheet=8|OwnerPartId=1|Location.X=1148|Location.Y=193|Corner.X=1132|Corner.Y=193|LineWidth=1|Color=16711680
|RECORD=13|OwnerIndex=1315|IsNotAccesible=T|IndexInSheet=9|OwnerPartId=1|Location.X=1132|Location.Y=197|Corner.X=1148|Corner.Y=197|LineWidth=1|Color=16711680
|RECORD=6|OwnerIndex=1315|IsNotAccesible=T|IndexInSheet=10|OwnerPartId=1|LineWidth=1|Color=16711680|LocationCount=2|X1=1140|Y1=200|X2=1140|Y2=197
|RECORD=6|OwnerIndex=1315|IsNotAccesible=T|IndexInSheet=11|OwnerPartId=1|LineWidth=1|Color=16711680|LocationCount=2|X1=1140|Y1=190|X2=1140|Y2=193
|RECORD=41|OwnerIndex=1315|IndexInSheet=12|OwnerPartId=-1|Location.X=1131|Location.Y=212|Color=8388608|FontID=1|IsHidden=T|Text=Kemet|Name=Manufacturer
|RECORD=41|OwnerIndex=1315|IndexInSheet=13|OwnerPartId=-1|Location.X=1131|Location.Y=212|Color=8388608|FontID=1|IsHidden=T|Text=C0603X104K5RACAUTO|Name=Part Number
|RECORD=34|OwnerIndex=1315|IndexInSheet=-1|OwnerPartId=-1|Location.X=1149|Location.Y=187|Color=8388608|FontID=4|Text=C29|Name=Designator|ReadOnlyState=1
|RECORD=41|OwnerIndex=1315|IndexInSheet=-1|OwnerPartId=-1|Location.X=1149|Location.Y=173|Color=8388608|FontID=4|Text=0.1uF|Name=Comment
|RECORD=44|OwnerIndex=1315
|RECORD=45|OwnerIndex=1336|IndexInSheet=-1|Description=Chip Capacitor, 2-Leads, Body 1.60x0.80mm, IPC Low Density|UseComponentLibrary=T|ModelName=CAPC1608X87X45ML20T05|ModelType=PCBLIB|DatafileCount=1|ModelDatafileEntity0=CAPC1608X87X45ML20T05|ModelDatafileKind0=PCBLib|IsCurrent=T|DatalinksLocked=T|DatabaseDatalinksLocked=T
|RECORD=46|OwnerIndex=1337
|RECORD=48|OwnerIndex=1337
|RECORD=41|OwnerIndex=1339|IndexInSheet=-1|OwnerPartId=-1|Color=8388608|FontID=1|Text=2D|Name=Available Preview Images
|RECORD=45|OwnerIndex=1336|IndexInSheet=-1|Description=Chip Capacitor, 2-Leads, Body 1.60x0.80mm, IPC High Density|UseComponentLibrary=T|ModelName=CAPC1608X87X45LL20T05|ModelType=PCBLIB|DatafileCount=1|ModelDatafileEntity0=CAPC1608X87X45LL20T05|ModelDatafileKind0=PCBLib|DatalinksLocked=T|DatabaseDatalinksLocked=T
|RECORD=46|OwnerIndex=1341
|RECORD=48|OwnerIndex=1341
|RECORD=41|OwnerIndex=1343|IndexInSheet=-1|OwnerPartId=-1|Color=8388608|FontID=1|Text=2D|Name=Available Preview Images
|RECORD=45|OwnerIndex=1336|IndexInSheet=-1|Description=Chip Capacitor, 2-Leads, Body 1.60x0.80mm, IPC Medium Density|UseComponentLibrary=T|ModelName=CAPC1608X87X45NL20T05|ModelType=PCBLIB|DatafileCount=1|ModelDatafileEntity0=CAPC1608X87X45NL20T05|ModelDatafileKind0=PCBLib|DatalinksLocked=T|DatabaseDatalinksLocked=T
|RECORD=46|OwnerIndex=1345
|RECORD=48|OwnerIndex=1345
|RECORD=41|OwnerIndex=1347|IndexInSheet=-1|OwnerPartId=-1|Color=8388608|FontID=1|Text=2D|Name=Available Preview Images
|RECORD=17|IndexInSheet=98|OwnerPartId=-1|ShowNetName=T|Location.X=1140|Location.Y=330|Orientation=1|Color=128|FontID=1|Text=+3.3V
|RECORD=17|IndexInSheet=99|OwnerPartId=-1|Style=4|ShowNetName=T|Location.X=1020|Location.Y=150|Orientation=3|Color=128|FontID=1|Text=GND
|RECORD=4|IndexInSheet=100|OwnerPartId=-1|Location.X=1090|Location.Y=700|Color=8388608|FontID=6|Text=TIMECARD INPUT
|RECORD=1|LibReference=WE-TVS-HS-4|ComponentDescription=TVS Diode WE-TVS-HS, VRWM=3.3V|PartCount=2|DisplayModeCount=1|IndexInSheet=101|OwnerPartId=-1|Location.X=660|Location.Y=400|Orientation=1|CurrentPartId=1|LibraryPath=*|SourceLibraryName=Altium Content Vault|TargetFileName=*|AreaColor=11599871|Color=128|PartIDLocked=F|DesignItemId=CMP-1486-00002-1|AllPinCount=4
|RECORD=14|OwnerIndex=1352|IsNotAccesible=T|OwnerPartId=1|Location.X=654|Location.Y=377|Corner.X=694|Corner.Y=415|AreaColor=11599871|IsSolid=T|Transparent=T
|RECORD=6|OwnerIndex=1352|IsNotAccesible=T|IndexInSheet=1|OwnerPartId=1|LineWidth=1|Color=16711680|LocationCount=4|X1=664|X1_Frac=10000|Y1=401|Y1_Frac=40000|X2=662|X2_Frac=10000|Y2=399|Y2_Frac=40000|X3=658|X3_Frac=10000|Y3=399|Y3_Frac=40000|X4=656|X4_Frac=10000|Y4=397|Y4_Frac=40000
|RECORD=7|OwnerIndex=1352|IsNotAccesible=T|IndexInSheet=2|OwnerPartId=1|LineWidth=1|Color=16711680|AreaColor=16711680|IsSolid=T|LocationCount=3|X1=664|X1_Frac=90000|Y1=393|Y1_Frac=50000|X2=659|X2_Frac=90000|Y2=398|Y2_Frac=50000|X3=654|X3_Frac=90000|Y3=393|Y3_Frac=50000
|RECORD=12|OwnerIndex=1352|IsNotAccesible=T|IndexInSheet=3|OwnerPartId=1|Location.X=671|Location.Y=398|Radius_Frac=63392|LineWidth=1|StartAngle=57.394|EndAngle=30.947
|RECORD=6|OwnerIndex=1352|IsNotAccesible=T|IndexInSheet=4|OwnerPartId=1|LineWidth=1|LocationCount=2|X1=680|Y1=398|X2=671|Y2=398
|RECORD=7|OwnerIndex=1352|IsNotAccesible=T|IndexInSheet=5|OwnerPartId=1|LineWidth=1|Color=16711680|AreaColor=16711680|LocationCount=3|X1=675|X1_Frac=90000|Y1=385|Y1_Frac=50000|X2=670|X2_Frac=90000|Y2=390|Y2_Frac=50000|X3=665|X3_Frac=90000|Y3=385|Y3_Frac=50000
|RECORD=6|OwnerIndex=1352|IsNotAccesible=T|IndexInSheet=6|OwnerPartId=1|LineWidth=1|Color=16711680|LocationCount=2|X1=667|Y1=391|X2=674|X2_Frac=87402|Y2=391
|RECORD=7|OwnerIndex=1352|IsNotAccesible=T|IndexInSheet=7|OwnerPartId=1|LineWidth=1|Color=16711680|AreaColor=16711680|LocationCount=3|X1=675|X1_Frac=90000|Y1=401|Y1_Frac=50000|X2=670|X2_Frac=90000|Y2=406|Y2_Frac=50000|X3=665|X3_Frac=90000|Y3=401|Y3_Frac=50000
|RECORD=6|OwnerIndex=1352|IsNotAccesible=T|IndexInSheet=8|OwnerPartId=1|LineWidth=1|Color=16711680|LocationCount=2|X1=667|Y1=407|X2=674|X2_Frac=87402|Y2=407
|RECORD=6|OwnerIndex=1352|IsNotAccesible=T|IndexInSheet=9|OwnerPartId=1|LineWidth=1|LocationCount=2|X1=671|Y1=391|X2=671|Y2=401
|RECORD=6|OwnerIndex=1352|IsNotAccesible=T|IndexInSheet=10|OwnerPartId=1|LineWidth=1|LocationCount=2|X1=671|Y1=407|X2=671|Y2=413
|RECORD=6|OwnerIndex=1352|IsNotAccesible=T|IndexInSheet=11|OwnerPartId=1|LineWidth=1|LocationCount=2|X1=660|Y1=400|X2=660|Y2=413
|RECORD=6|OwnerIndex=1352|IsNotAccesible=T|IndexInSheet=12|OwnerPartId=1|LineWidth=1|LocationCount=2|X1=660|Y1=379|X2=660|Y2=393
|RECORD=6|OwnerIndex=1352|IsNotAccesible=T|IndexInSheet=13|OwnerPartId=1|LineWidth=1|LocationCount=2|X1=671|Y1=379|X2=671|Y2=385
|RECORD=6|OwnerIndex=1352|IsNotAccesible=T|IndexInSheet=14|OwnerPartId=1|LineWidth=1|LocationCount=2|X1=660|Y1=379|X2=688|Y2=379
|RECORD=6|OwnerIndex=1352|IsNotAccesible=T|IndexInSheet=15|OwnerPartId=1|LineWidth=1|LocationCount=2|X1=660|Y1=413|X2=688|Y2=413
|RECORD=6|OwnerIndex=1352|IsNotAccesible=T|IndexInSheet=16|OwnerPartId=1|LineWidth=1|LocationCount=2|X1=680|Y1=394|X2=680|Y2=380
|RECORD=2|OwnerIndex=1352|OwnerPartId=1|FormalType=1|Electrical=4|PinConglomerate=51|PinLength=10|Location.X=660|Location.Y=380|Name=GND|Designator=1|PinPropagationDelay=0.000000E+000
|RECORD=2|OwnerIndex=1352|OwnerPartId=1|FormalType=1|Electrical=4|PinConglomerate=51|PinLength=10|Location.X=680|Location.Y=380|Name=I/O1|Designator=2|PinPropagationDelay=0.000000E+000
|RECORD=2|OwnerIndex=1352|OwnerPartId=1|FormalType=1|Electrical=4|PinConglomerate=49|PinLength=10|Location.X=680|Location.Y=410|Name=I/O2|Designator=3|PinPropagationDelay=0.000000E+000
|RECORD=2|OwnerIndex=1352|OwnerPartId=1|FormalType=1|Electrical=4|PinConglomerate=49|PinLength=10|Location.X=660|Location.Y=410|Name=VDD|Designator=4|PinPropagationDelay=0.000000E+000
|RECORD=12|OwnerIndex=1352|IsNotAccesible=T|IndexInSheet=21|OwnerPartId=1|Location.X=660|Location.Y=413|Radius_Frac=63392|LineWidth=1|StartAngle=57.394|EndAngle=30.947
|RECORD=12|OwnerIndex=1352|IsNotAccesible=T|IndexInSheet=22|OwnerPartId=1|Location.X=660|Location.Y=379|Radius_Frac=63392|LineWidth=1|StartAngle=57.394|EndAngle=30.947
|RECORD=12|OwnerIndex=1352|IsNotAccesible=T|IndexInSheet=23|OwnerPartId=1|Location.X=688|Location.Y=394|Radius_Frac=63392|LineWidth=1|StartAngle=57.394|EndAngle=30.947
|RECORD=6|OwnerIndex=1352|IsNotAccesible=T|IndexInSheet=24|OwnerPartId=1|LineWidth=1|LocationCount=2|X1=680|Y1=394|X2=688|Y2=394
|RECORD=7|OwnerIndex=1352|IsNotAccesible=T|IndexInSheet=25|OwnerPartId=1|LineWidth=1|Color=16711680|AreaColor=16711680|LocationCount=3|X1=692|X1_Frac=90000|Y1=385|Y1_Frac=50000|X2=687|X2_Frac=90000|Y2=390|Y2_Frac=50000|X3=682|X3_Frac=90000|Y3=385|Y3_Frac=50000
|RECORD=6|OwnerIndex=1352|IsNotAccesible=T|IndexInSheet=26|OwnerPartId=1|LineWidth=1|Color=16711680|LocationCount=2|X1=684|Y1=391|X2=691|X2_Frac=87402|Y2=391
|RECORD=7|OwnerIndex=1352|IsNotAccesible=T|IndexInSheet=27|OwnerPartId=1|LineWidth=1|Color=16711680|AreaColor=16711680|LocationCount=3|X1=692|X1_Frac=90000|Y1=401|Y1_Frac=50000|X2=687|X2_Frac=90000|Y2=406|Y2_Frac=50000|X3=682|X3_Frac=90000|Y3=401|Y3_Frac=50000
|RECORD=6|OwnerIndex=1352|IsNotAccesible=T|IndexInSheet=28|OwnerPartId=1|LineWidth=1|Color=16711680|LocationCount=2|X1=684|Y1=407|X2=691|X2_Frac=87402|Y2=407
|RECORD=6|OwnerIndex=1352|IsNotAccesible=T|IndexInSheet=29|OwnerPartId=1|LineWidth=1|LocationCount=2|X1=688|Y1=391|X2=688|Y2=401
|RECORD=6|OwnerIndex=1352|IsNotAccesible=T|IndexInSheet=30|OwnerPartId=1|LineWidth=1|LocationCount=2|X1=688|Y1=407|X2=688|Y2=413
|RECORD=6|OwnerIndex=1352|IsNotAccesible=T|IndexInSheet=31|OwnerPartId=1|LineWidth=1|LocationCount=2|X1=688|Y1=379|X2=688|Y2=385
|RECORD=12|OwnerIndex=1352|IsNotAccesible=T|IndexInSheet=32|OwnerPartId=1|Location.X=671|Location.Y=413|Radius_Frac=63392|LineWidth=1|StartAngle=57.394|EndAngle=30.947
|RECORD=12|OwnerIndex=1352|IsNotAccesible=T|IndexInSheet=33|OwnerPartId=1|Location.X=671|Location.Y=379|Radius_Frac=63392|LineWidth=1|StartAngle=57.394|EndAngle=30.947
|RECORD=6|OwnerIndex=1352|IsNotAccesible=T|IndexInSheet=34|OwnerPartId=1|LineWidth=1|LocationCount=2|X1=680|Y1=398|X2=680|Y2=415
|RECORD=41|OwnerIndex=1352|IndexInSheet=35|OwnerPartId=-1|Location.X=653|Location.X_Frac=90000|Location.Y=422|Color=8388608|FontID=1|IsHidden=T|Text=8240136|Name=PartNumber
|RECORD=41|OwnerIndex=1352|IndexInSheet=36|OwnerPartId=-1|Location.X=653|Location.X_Frac=90000|Location.Y=422|Color=8388608|FontID=1|IsHidden=T|Text=Manufacturer URL|Name=ComponentLink1Description
|RECORD=41|OwnerIndex=1352|IndexInSheet=37|OwnerPartId=-1|Location.X=653|Location.X_Frac=90000|Location.Y=422|Color=8388608|FontID=1|IsHidden=T|Text=Wuerth Elektronik|Name=Manufacturer
|RECORD=41|OwnerIndex=1352|IndexInSheet=38|OwnerPartId=-1|Location.X=653|Location.X_Frac=90000|Location.Y=422|Color=8388608|FontID=1|IsHidden=T|Text=SOT143-4L|Name=PackageReference
|RECORD=41|OwnerIndex=1352|IndexInSheet=39|OwnerPartId=-1|Location.X=653|Location.X_Frac=90000|Location.Y=422|Color=8388608|FontID=2|IsHidden=T|Text=http://www.we-online.com|Name=ComponentLink1URL
|RECORD=41|OwnerIndex=1352|IndexInSheet=40|OwnerPartId=-1|Location.X=653|Location.X_Frac=90000|Location.Y=422|Color=8388608|FontID=1|IsHidden=T|Text=3.3V|Name=Reverse Stand Off Voltage
|RECORD=41|OwnerIndex=1352|IndexInSheet=41|OwnerPartId=-1|Location.X=653|Location.X_Frac=90000|Location.Y=422|Color=8388608|FontID=1|IsHidden=T|Text=Datasheet|Name=ComponentLink2Description
|RECORD=41|OwnerIndex=1352|IndexInSheet=42|OwnerPartId=-1|Location.X=653|Location.X_Frac=90000|Location.Y=422|Color=8388608|FontID=2|IsHidden=T|Text=http://katalog.we-online.de/kataloge/eisos/media/pdf/8240136.pdf|Name=ComponentLink2URL
|RECORD=34|OwnerIndex=1352|IndexInSheet=-1|OwnerPartId=-1|Location.X=694|Location.Y=406|Color=8388608|FontID=1|Text=D2|Name=Designator|ReadOnlyState=1
|RECORD=41|OwnerIndex=1352|IndexInSheet=-1|OwnerPartId=-1|Location.X=694|Location.Y=396|Color=8388608|FontID=1|Text=8240136|Name=Comment
|RECORD=44|OwnerIndex=1352
|RECORD=45|OwnerIndex=1402|IndexInSheet=-1|Description=SOT143-4L, 4-Leads, Body 2.95x2.4mm, Pitch 1.70/1.90mm|UseComponentLibrary=T|ModelName=SOT143-4L|ModelType=PCBLIB|IsCurrent=T|DatalinksLocked=T|DatabaseDatalinksLocked=T
|RECORD=46|OwnerIndex=1403
|RECORD=48|OwnerIndex=1403
|RECORD=41|OwnerIndex=1405|IndexInSheet=-1|OwnerPartId=-1|Color=8388608|FontID=1|IsHidden=T|Text=2D|Name=Available Preview Images
|RECORD=27|IndexInSheet=102|OwnerPartId=-1|LineWidth=1|Color=8388608|LocationCount=2|X1=750|Y1=890|X2=750|Y2=880
|RECORD=27|IndexInSheet=103|OwnerPartId=-1|LineWidth=1|Color=8388608|LocationCount=2|X1=850|Y1=890|X2=850|Y2=880
|RECORD=27|IndexInSheet=104|OwnerPartId=-1|LineWidth=1|Color=8388608|LocationCount=2|X1=950|Y1=890|X2=950|Y2=880
|RECORD=27|IndexInSheet=105|OwnerPartId=-1|LineWidth=1|Color=8388608|LocationCount=2|X1=1050|Y1=890|X2=1050|Y2=880
|RECORD=27|IndexInSheet=106|OwnerPartId=-1|LineWidth=1|Color=8388608|LocationCount=3|X1=1300|Y1=660|X2=1270|Y2=660|X3=1270|Y3=570
|RECORD=27|IndexInSheet=107|OwnerPartId=-1|LineWidth=1|Color=8388608|LocationCount=3|X1=710|Y1=660|X2=680|Y2=660|X3=680|Y3=570
|RECORD=27|IndexInSheet=108|OwnerPartId=-1|LineWidth=1|Color=8388608|LocationCount=2|X1=1300|Y1=250|X2=1270|Y2=250
|RECORD=27|IndexInSheet=109|OwnerPartId=-1|LineWidth=1|Color=8388608|LocationCount=3|X1=1300|Y1=340|X2=1270|Y2=340|X3=1270|Y3=250
|RECORD=27|IndexInSheet=110|OwnerPartId=-1|LineWidth=1|Color=8388608|LocationCount=2|X1=710|Y1=220|X2=680|Y2=220
|RECORD=27|IndexInSheet=111|OwnerPartId=-1|LineWidth=1|Color=8388608|LocationCount=3|X1=710|Y1=310|X2=680|Y2=310|X3=680|Y3=220
|RECORD=27|IndexInSheet=112|OwnerPartId=-1|LineWidth=1|Color=8388608|LocationCount=2|X1=1350|Y1=480|X2=1350|Y2=470
|RECORD=27|IndexInSheet=113|OwnerPartId=-1|LineWidth=1|Color=8388608|LocationCount=3|X1=750|Y1=840|X2=750|Y2=820|X3=740|Y3=820
|RECORD=27|IndexInSheet=114|OwnerPartId=-1|LineWidth=1|Color=8388608|LocationCount=3|X1=850|Y1=840|X2=850|Y2=820|X3=840|Y3=820
|RECORD=27|IndexInSheet=115|OwnerPartId=-1|LineWidth=1|Color=8388608|LocationCount=3|X1=950|Y1=840|X2=950|Y2=820|X3=940|Y3=820
|RECORD=27|IndexInSheet=116|OwnerPartId=-1|LineWidth=1|Color=8388608|LocationCount=3|X1=1050|Y1=840|X2=1050|Y2=820|X3=1040|Y3=820
|RECORD=27|IndexInSheet=117|OwnerPartId=-1|LineWidth=1|Color=8388608|LocationCount=2|X1=1340|Y1=540|X2=1340|Y2=480
|RECORD=27|IndexInSheet=118|OwnerPartId=-1|LineWidth=1|Color=8388608|LocationCount=2|X1=1330|Y1=540|X2=1330|Y2=480
|RECORD=27|IndexInSheet=119|OwnerPartId=-1|LineWidth=1|Color=8388608|LocationCount=2|X1=750|Y1=540|X2=750|Y2=480
|RECORD=27|IndexInSheet=120|OwnerPartId=-1|LineWidth=1|Color=8388608|LocationCount=2|X1=740|Y1=540|X2=740|Y2=480
|RECORD=27|IndexInSheet=121|OwnerPartId=-1|LineWidth=1|Color=8388608|LocationCount=2|X1=750|Y1=190|X2=750|Y2=130
|RECORD=27|IndexInSheet=122|OwnerPartId=-1|LineWidth=1|Color=8388608|LocationCount=2|X1=740|Y1=190|X2=740|Y2=130
|RECORD=27|IndexInSheet=123|OwnerPartId=-1|LineWidth=1|Color=8388608|LocationCount=2|X1=1340|Y1=220|X2=1340|Y2=160
|RECORD=27|IndexInSheet=124|OwnerPartId=-1|LineWidth=1|Color=8388608|LocationCount=2|X1=1330|Y1=220|X2=1330|Y2=160
|RECORD=27|IndexInSheet=125|OwnerPartId=-1|LineWidth=1|Color=8388608|LocationCount=2|X1=750|Y1=630|X2=750|Y2=620
|RECORD=27|IndexInSheet=126|OwnerPartId=-1|LineWidth=1|Color=8388608|LocationCount=5|X1=1320|Y1=630|X2=1320|Y2=620|X3=1340|Y3=620|X4=1380|Y4=620|X5=1380|Y5=610
|RECORD=27|IndexInSheet=127|OwnerPartId=-1|LineWidth=1|Color=8388608|LocationCount=2|X1=1340|Y1=630|X2=1340|Y2=620
|RECORD=27|IndexInSheet=128|OwnerPartId=-1|LineWidth=1|Color=8388608|LocationCount=5|X1=1320|Y1=310|X2=1320|Y2=300|X3=1340|Y3=300|X4=1380|Y4=300|X5=1380|Y5=290
|RECORD=27|IndexInSheet=129|OwnerPartId=-1|LineWidth=1|Color=8388608|LocationCount=2|X1=1340|Y1=310|X2=1340|Y2=300
|RECORD=27|IndexInSheet=130|OwnerPartId=-1|LineWidth=1|Color=8388608|LocationCount=2|X1=750|Y1=280|X2=750|Y2=270
|RECORD=27|IndexInSheet=131|OwnerPartId=-1|LineWidth=1|Color=8388608|LocationCount=5|X1=730|Y1=630|X2=730|Y2=620|X3=750|Y3=620|X4=790|Y4=620|X5=790|Y5=610
|RECORD=27|IndexInSheet=132|OwnerPartId=-1|LineWidth=1|Color=8388608|LocationCount=3|X1=580|Y1=550|X2=610|Y2=550|X3=610|Y3=470
|RECORD=27|IndexInSheet=133|OwnerPartId=-1|LineWidth=1|Color=8388608|LocationCount=2|X1=650|Y1=570|X2=680|Y2=570
|RECORD=27|IndexInSheet=134|OwnerPartId=-1|LineWidth=1|Color=8388608|LocationCount=2|X1=610|Y1=570|X2=580|Y2=570
|RECORD=27|IndexInSheet=135|OwnerPartId=-1|LineWidth=1|Color=8388608|LocationCount=3|X1=500|Y1=590|X2=480|Y2=590|X3=480|Y3=470
|RECORD=27|IndexInSheet=136|OwnerPartId=-1|LineWidth=1|Color=8388608|LocationCount=3|X1=500|Y1=610|X2=430|Y2=610|X3=430|Y3=530
|RECORD=27|IndexInSheet=137|OwnerPartId=-1|LineWidth=1|Color=8388608|LocationCount=2|X1=430|Y1=500|X2=430|Y2=470
|RECORD=27|IndexInSheet=138|OwnerPartId=-1|LineWidth=1|Color=8388608|LocationCount=2|X1=500|Y1=570|X2=410|Y2=570
|RECORD=27|IndexInSheet=139|OwnerPartId=-1|LineWidth=1|Color=8388608|LocationCount=2|X1=430|Y1=610|X2=430|Y2=650
|RECORD=27|IndexInSheet=140|OwnerPartId=-1|LineWidth=1|Color=8388608|LocationCount=3|X1=580|Y1=200|X2=610|Y2=200|X3=610|Y3=120
|RECORD=27|IndexInSheet=141|OwnerPartId=-1|LineWidth=1|Color=8388608|LocationCount=2|X1=610|Y1=220|X2=580|Y2=220
|RECORD=27|IndexInSheet=142|OwnerPartId=-1|LineWidth=1|Color=8388608|LocationCount=3|X1=500|Y1=240|X2=480|Y2=240|X3=480|Y3=120
|RECORD=27|IndexInSheet=143|OwnerPartId=-1|LineWidth=1|Color=8388608|LocationCount=3|X1=500|Y1=260|X2=430|Y2=260|X3=430|Y3=180
|RECORD=27|IndexInSheet=144|OwnerPartId=-1|LineWidth=1|Color=8388608|LocationCount=2|X1=430|Y1=150|X2=430|Y2=120
|RECORD=27|IndexInSheet=145|OwnerPartId=-1|LineWidth=1|Color=8388608|LocationCount=2|X1=500|Y1=220|X2=410|Y2=220
|RECORD=27|IndexInSheet=146|OwnerPartId=-1|LineWidth=1|Color=8388608|LocationCount=2|X1=430|Y1=260|X2=430|Y2=300
|RECORD=27|IndexInSheet=147|OwnerPartId=-1|LineWidth=1|Color=8388608|LocationCount=2|X1=680|Y1=220|X2=650|Y2=220
|RECORD=27|IndexInSheet=148|OwnerPartId=-1|LineWidth=1|Color=8388608|LocationCount=2|X1=1140|Y1=500|X2=1140|Y2=470
|RECORD=27|IndexInSheet=149|OwnerPartId=-1|LineWidth=1|Color=8388608|LocationCount=2|X1=1270|Y1=570|X2=1240|Y2=570
|RECORD=27|IndexInSheet=150|OwnerPartId=-1|LineWidth=1|Color=8388608|LocationCount=2|X1=1240|Y1=250|X2=1270|Y2=250
|RECORD=27|IndexInSheet=151|OwnerPartId=-1|LineWidth=1|Color=8388608|LocationCount=3|X1=1020|Y1=470|X2=1020|Y2=550|X3=1040|Y3=550
|RECORD=27|IndexInSheet=152|OwnerPartId=-1|LineWidth=1|Color=8388608|LocationCount=3|X1=1140|Y1=530|X2=1140|Y2=610|X3=1140|Y3=650
|RECORD=27|IndexInSheet=153|OwnerPartId=-1|LineWidth=1|Color=8388608|LocationCount=2|X1=1120|Y1=610|X2=1140|Y2=610
|RECORD=27|IndexInSheet=154|OwnerPartId=-1|LineWidth=1|Color=8388608|LocationCount=3|X1=1120|Y1=590|X2=1190|Y2=590|X3=1190|Y3=470
|RECORD=27|IndexInSheet=155|OwnerPartId=-1|LineWidth=1|Color=8388608|LocationCount=2|X1=1200|Y1=570|X2=1120|Y2=570
|RECORD=27|IndexInSheet=156|OwnerPartId=-1|LineWidth=1|Color=8388608|LocationCount=2|X1=1040|Y1=570|X2=1000|Y2=570
|RECORD=27|IndexInSheet=157|OwnerPartId=-1|LineWidth=1|Color=8388608|LocationCount=2|X1=1200|Y1=250|X2=1120|Y2=250
|RECORD=27|IndexInSheet=158|OwnerPartId=-1|LineWidth=1|Color=8388608|LocationCount=3|X1=1140|Y1=210|X2=1140|Y2=290|X3=1140|Y3=330
|RECORD=27|IndexInSheet=159|OwnerPartId=-1|LineWidth=1|Color=8388608|LocationCount=2|X1=1120|Y1=290|X2=1140|Y2=290
|RECORD=27|IndexInSheet=160|OwnerPartId=-1|LineWidth=1|Color=8388608|LocationCount=3|X1=1120|Y1=270|X2=1190|Y2=270|X3=1190|Y3=150
|RECORD=27|IndexInSheet=161|OwnerPartId=-1|LineWidth=1|Color=8388608|LocationCount=2|X1=1140|Y1=150|X2=1140|Y2=180
|RECORD=27|IndexInSheet=162|OwnerPartId=-1|LineWidth=1|Color=8388608|LocationCount=2|X1=1040|Y1=250|X2=1000|Y2=250
|RECORD=27|IndexInSheet=163|OwnerPartId=-1|LineWidth=1|Color=8388608|LocationCount=3|X1=1020|Y1=150|X2=1020|Y2=230|X3=1040|Y3=230
|RECORD=27|IndexInSheet=164|OwnerPartId=-1|LineWidth=1|Color=8388608|LocationCount=2|X1=760|Y1=480|X2=760|Y2=470
|RECORD=27|IndexInSheet=165|OwnerPartId=-1|LineWidth=1|Color=8388608|LocationCount=6|X1=760|Y1=540|X2=760|Y2=480|X3=750|Y3=480|X4=740|Y4=480|X5=730|Y5=480|X6=730|Y6=540
|RECORD=27|IndexInSheet=166|OwnerPartId=-1|LineWidth=1|Color=8388608|LocationCount=2|X1=760|Y1=130|X2=760|Y2=120
|RECORD=27|IndexInSheet=167|OwnerPartId=-1|LineWidth=1|Color=8388608|LocationCount=6|X1=760|Y1=190|X2=760|Y2=130|X3=750|Y3=130|X4=740|Y4=130|X5=730|Y5=130|X6=730|Y6=190
|RECORD=27|IndexInSheet=168|OwnerPartId=-1|LineWidth=1|Color=8388608|LocationCount=5|X1=730|Y1=280|X2=730|Y2=270|X3=750|Y3=270|X4=790|Y4=270|X5=790|Y5=260
|RECORD=17|IndexInSheet=169|OwnerPartId=-1|ShowNetName=T|Location.X=660|Location.Y=450|Orientation=1|Color=128|FontID=1|Text=+3.3V
|RECORD=17|IndexInSheet=170|OwnerPartId=-1|Style=4|ShowNetName=T|Location.X=660|Location.Y=350|Orientation=3|Color=128|FontID=1|Text=GND
|RECORD=27|IndexInSheet=171|OwnerPartId=-1|LineWidth=1|Color=8388608|LocationCount=2|X1=660|Y1=370|X2=660|Y2=350
|RECORD=27|IndexInSheet=172|OwnerPartId=-1|LineWidth=1|Color=8388608|LocationCount=2|X1=660|Y1=420|X2=660|Y2=450
|RECORD=27|IndexInSheet=173|OwnerPartId=-1|LineWidth=1|Color=8388608|LocationCount=3|X1=680|Y1=420|X2=680|Y2=570|X3=710|Y3=570
|RECORD=27|IndexInSheet=174|OwnerPartId=-1|LineWidth=1|Color=8388608|LocationCount=2|X1=680|Y1=370|X2=680|Y2=310
|RECORD=27|IndexInSheet=175|OwnerPartId=-1|LineWidth=1|Color=8388608|LocationCount=6|X1=1350|Y1=540|X2=1350|Y2=480|X3=1340|Y3=480|X4=1330|Y4=480|X5=1320|Y5=480|X6=1320|Y6=540
|RECORD=27|IndexInSheet=176|OwnerPartId=-1|LineWidth=1|Color=8388608|LocationCount=2|X1=1350|Y1=150|X2=1350|Y2=160
|RECORD=27|IndexInSheet=177|OwnerPartId=-1|LineWidth=1|Color=8388608|LocationCount=6|X1=1350|Y1=220|X2=1350|Y2=160|X3=1340|Y3=160|X4=1330|Y4=160|X5=1320|Y5=160|X6=1320|Y6=220
|RECORD=1|LibReference=WE-TVS-HS-4|ComponentDescription=TVS Diode WE-TVS-HS, VRWM=3.3V|PartCount=2|DisplayModeCount=1|IndexInSheet=178|OwnerPartId=-1|Location.X=1250|Location.Y=430|Orientation=1|CurrentPartId=1|LibraryPath=*|SourceLibraryName=Altium Content Vault|TargetFileName=*|AreaColor=11599871|Color=128|PartIDLocked=F|DesignItemId=CMP-1486-00002-1|AllPinCount=4
|RECORD=14|OwnerIndex=1483|IsNotAccesible=T|OwnerPartId=1|Location.X=1244|Location.Y=407|Corner.X=1284|Corner.Y=445|AreaColor=11599871|IsSolid=T|Transparent=T
|RECORD=6|OwnerIndex=1483|IsNotAccesible=T|IndexInSheet=1|OwnerPartId=1|LineWidth=1|Color=16711680|LocationCount=4|X1=1254|X1_Frac=10000|Y1=431|Y1_Frac=40000|X2=1252|X2_Frac=10000|Y2=429|Y2_Frac=40000|X3=1248|X3_Frac=10000|Y3=429|Y3_Frac=40000|X4=1246|X4_Frac=10000|Y4=427|Y4_Frac=40000
|RECORD=7|OwnerIndex=1483|IsNotAccesible=T|IndexInSheet=2|OwnerPartId=1|LineWidth=1|Color=16711680|AreaColor=16711680|IsSolid=T|LocationCount=3|X1=1254|X1_Frac=90000|Y1=423|Y1_Frac=50000|X2=1249|X2_Frac=90000|Y2=428|Y2_Frac=50000|X3=1244|X3_Frac=90000|Y3=423|Y3_Frac=50000
|RECORD=12|OwnerIndex=1483|IsNotAccesible=T|IndexInSheet=3|OwnerPartId=1|Location.X=1261|Location.Y=428|Radius_Frac=63392|LineWidth=1|StartAngle=57.394|EndAngle=30.947
|RECORD=6|OwnerIndex=1483|IsNotAccesible=T|IndexInSheet=4|OwnerPartId=1|LineWidth=1|LocationCount=2|X1=1270|Y1=428|X2=1261|Y2=428
|RECORD=7|OwnerIndex=1483|IsNotAccesible=T|IndexInSheet=5|OwnerPartId=1|LineWidth=1|Color=16711680|AreaColor=16711680|LocationCount=3|X1=1265|X1_Frac=90000|Y1=415|Y1_Frac=50000|X2=1260|X2_Frac=90000|Y2=420|Y2_Frac=50000|X3=1255|X3_Frac=90000|Y3=415|Y3_Frac=50000
|RECORD=6|OwnerIndex=1483|IsNotAccesible=T|IndexInSheet=6|OwnerPartId=1|LineWidth=1|Color=16711680|LocationCount=2|X1=1257|Y1=421|X2=1264|X2_Frac=87402|Y2=421
|RECORD=7|OwnerIndex=1483|IsNotAccesible=T|IndexInSheet=7|OwnerPartId=1|LineWidth=1|Color=16711680|AreaColor=16711680|LocationCount=3|X1=1265|X1_Frac=90000|Y1=431|Y1_Frac=50000|X2=1260|X2_Frac=90000|Y2=436|Y2_Frac=50000|X3=1255|X3_Frac=90000|Y3=431|Y3_Frac=50000
|RECORD=6|OwnerIndex=1483|IsNotAccesible=T|IndexInSheet=8|OwnerPartId=1|LineWidth=1|Color=16711680|LocationCount=2|X1=1257|Y1=437|X2=1264|X2_Frac=87402|Y2=437
|RECORD=6|OwnerIndex=1483|IsNotAccesible=T|IndexInSheet=9|OwnerPartId=1|LineWidth=1|LocationCount=2|X1=1261|Y1=421|X2=1261|Y2=431
|RECORD=6|OwnerIndex=1483|IsNotAccesible=T|IndexInSheet=10|OwnerPartId=1|LineWidth=1|LocationCount=2|X1=1261|Y1=437|X2=1261|Y2=443
|RECORD=6|OwnerIndex=1483|IsNotAccesible=T|IndexInSheet=11|OwnerPartId=1|LineWidth=1|LocationCount=2|X1=1250|Y1=430|X2=1250|Y2=443
|RECORD=6|OwnerIndex=1483|IsNotAccesible=T|IndexInSheet=12|OwnerPartId=1|LineWidth=1|LocationCount=2|X1=1250|Y1=409|X2=1250|Y2=423
|RECORD=6|OwnerIndex=1483|IsNotAccesible=T|IndexInSheet=13|OwnerPartId=1|LineWidth=1|LocationCount=2|X1=1261|Y1=409|X2=1261|Y2=415
|RECORD=6|OwnerIndex=1483|IsNotAccesible=T|IndexInSheet=14|OwnerPartId=1|LineWidth=1|LocationCount=2|X1=1250|Y1=409|X2=1278|Y2=409
|RECORD=6|OwnerIndex=1483|IsNotAccesible=T|IndexInSheet=15|OwnerPartId=1|LineWidth=1|LocationCount=2|X1=1250|Y1=443|X2=1278|Y2=443
|RECORD=6|OwnerIndex=1483|IsNotAccesible=T|IndexInSheet=16|OwnerPartId=1|LineWidth=1|LocationCount=2|X1=1270|Y1=424|X2=1270|Y2=410
|RECORD=2|OwnerIndex=1483|OwnerPartId=1|FormalType=1|Electrical=4|PinConglomerate=51|PinLength=10|Location.X=1250|Location.Y=410|Name=GND|Designator=1|PinPropagationDelay=0.000000E+000
|RECORD=2|OwnerIndex=1483|OwnerPartId=1|FormalType=1|Electrical=4|PinConglomerate=51|PinLength=10|Location.X=1270|Location.Y=410|Name=I/O1|Designator=2|PinPropagationDelay=0.000000E+000
|RECORD=2|OwnerIndex=1483|OwnerPartId=1|FormalType=1|Electrical=4|PinConglomerate=49|PinLength=10|Location.X=1270|Location.Y=440|Name=I/O2|Designator=3|PinPropagationDelay=0.000000E+000
|RECORD=2|OwnerIndex=1483|OwnerPartId=1|FormalType=1|Electrical=4|PinConglomerate=49|PinLength=10|Location.X=1250|Location.Y=440|Name=VDD|Designator=4|PinPropagationDelay=0.000000E+000
|RECORD=12|OwnerIndex=1483|IsNotAccesible=T|IndexInSheet=21|OwnerPartId=1|Location.X=1250|Location.Y=443|Radius_Frac=63392|LineWidth=1|StartAngle=57.394|EndAngle=30.947
|RECORD=12|OwnerIndex=1483|IsNotAccesible=T|IndexInSheet=22|OwnerPartId=1|Location.X=1250|Location.Y=409|Radius_Frac=63392|LineWidth=1|StartAngle=57.394|EndAngle=30.947
|RECORD=12|OwnerIndex=1483|IsNotAccesible=T|IndexInSheet=23|OwnerPartId=1|Location.X=1278|Location.Y=424|Radius_Frac=63392|LineWidth=1|StartAngle=57.394|EndAngle=30.947
|RECORD=6|OwnerIndex=1483|IsNotAccesible=T|IndexInSheet=24|OwnerPartId=1|LineWidth=1|LocationCount=2|X1=1270|Y1=424|X2=1278|Y2=424
|RECORD=7|OwnerIndex=1483|IsNotAccesible=T|IndexInSheet=25|OwnerPartId=1|LineWidth=1|Color=16711680|AreaColor=16711680|LocationCount=3|X1=1282|X1_Frac=90000|Y1=415|Y1_Frac=50000|X2=1277|X2_Frac=90000|Y2=420|Y2_Frac=50000|X3=1272|X3_Frac=90000|Y3=415|Y3_Frac=50000
|RECORD=6|OwnerIndex=1483|IsNotAccesible=T|IndexInSheet=26|OwnerPartId=1|LineWidth=1|Color=16711680|LocationCount=2|X1=1274|Y1=421|X2=1281|X2_Frac=87402|Y2=421
|RECORD=7|OwnerIndex=1483|IsNotAccesible=T|IndexInSheet=27|OwnerPartId=1|LineWidth=1|Color=16711680|AreaColor=16711680|LocationCount=3|X1=1282|X1_Frac=90000|Y1=431|Y1_Frac=50000|X2=1277|X2_Frac=90000|Y2=436|Y2_Frac=50000|X3=1272|X3_Frac=90000|Y3=431|Y3_Frac=50000
|RECORD=6|OwnerIndex=1483|IsNotAccesible=T|IndexInSheet=28|OwnerPartId=1|LineWidth=1|Color=16711680|LocationCount=2|X1=1274|Y1=437|X2=1281|X2_Frac=87402|Y2=437
|RECORD=6|OwnerIndex=1483|IsNotAccesible=T|IndexInSheet=29|OwnerPartId=1|LineWidth=1|LocationCount=2|X1=1278|Y1=421|X2=1278|Y2=431
|RECORD=6|OwnerIndex=1483|IsNotAccesible=T|IndexInSheet=30|OwnerPartId=1|LineWidth=1|LocationCount=2|X1=1278|Y1=437|X2=1278|Y2=443
|RECORD=6|OwnerIndex=1483|IsNotAccesible=T|IndexInSheet=31|OwnerPartId=1|LineWidth=1|LocationCount=2|X1=1278|Y1=409|X2=1278|Y2=415
|RECORD=12|OwnerIndex=1483|IsNotAccesible=T|IndexInSheet=32|OwnerPartId=1|Location.X=1261|Location.Y=443|Radius_Frac=63392|LineWidth=1|StartAngle=57.394|EndAngle=30.947
|RECORD=12|OwnerIndex=1483|IsNotAccesible=T|IndexInSheet=33|OwnerPartId=1|Location.X=1261|Location.Y=409|Radius_Frac=63392|LineWidth=1|StartAngle=57.394|EndAngle=30.947
|RECORD=6|OwnerIndex=1483|IsNotAccesible=T|IndexInSheet=34|OwnerPartId=1|LineWidth=1|LocationCount=2|X1=1270|Y1=428|X2=1270|Y2=445
|RECORD=41|OwnerIndex=1483|IndexInSheet=35|OwnerPartId=-1|Location.X=1243|Location.X_Frac=90000|Location.Y=452|Color=8388608|FontID=1|IsHidden=T|Text=8240136|Name=PartNumber
|RECORD=41|OwnerIndex=1483|IndexInSheet=36|OwnerPartId=-1|Location.X=1243|Location.X_Frac=90000|Location.Y=452|Color=8388608|FontID=1|IsHidden=T|Text=Manufacturer URL|Name=ComponentLink1Description
|RECORD=41|OwnerIndex=1483|IndexInSheet=37|OwnerPartId=-1|Location.X=1243|Location.X_Frac=90000|Location.Y=452|Color=8388608|FontID=1|IsHidden=T|Text=Wuerth Elektronik|Name=Manufacturer
|RECORD=41|OwnerIndex=1483|IndexInSheet=38|OwnerPartId=-1|Location.X=1243|Location.X_Frac=90000|Location.Y=452|Color=8388608|FontID=1|IsHidden=T|Text=SOT143-4L|Name=PackageReference
|RECORD=41|OwnerIndex=1483|IndexInSheet=39|OwnerPartId=-1|Location.X=1243|Location.X_Frac=90000|Location.Y=452|Color=8388608|FontID=2|IsHidden=T|Text=http://www.we-online.com|Name=ComponentLink1URL
|RECORD=41|OwnerIndex=1483|IndexInSheet=40|OwnerPartId=-1|Location.X=1243|Location.X_Frac=90000|Location.Y=452|Color=8388608|FontID=1|IsHidden=T|Text=3.3V|Name=Reverse Stand Off Voltage
|RECORD=41|OwnerIndex=1483|IndexInSheet=41|OwnerPartId=-1|Location.X=1243|Location.X_Frac=90000|Location.Y=452|Color=8388608|FontID=1|IsHidden=T|Text=Datasheet|Name=ComponentLink2Description
|RECORD=41|OwnerIndex=1483|IndexInSheet=42|OwnerPartId=-1|Location.X=1243|Location.X_Frac=90000|Location.Y=452|Color=8388608|FontID=2|IsHidden=T|Text=http://katalog.we-online.de/kataloge/eisos/media/pdf/8240136.pdf|Name=ComponentLink2URL
|RECORD=34|OwnerIndex=1483|IndexInSheet=-1|OwnerPartId=-1|Location.X=1284|Location.Y=436|Color=8388608|FontID=1|Text=D1|Name=Designator|ReadOnlyState=1
|RECORD=41|OwnerIndex=1483|IndexInSheet=-1|OwnerPartId=-1|Location.X=1284|Location.Y=426|Color=8388608|FontID=1|Text=8240136|Name=Comment
|RECORD=44|OwnerIndex=1483
|RECORD=45|OwnerIndex=1533|IndexInSheet=-1|Description=SOT143-4L, 4-Leads, Body 2.95x2.4mm, Pitch 1.70/1.90mm|UseComponentLibrary=T|ModelName=SOT143-4L|ModelType=PCBLIB|IsCurrent=T|DatalinksLocked=T|DatabaseDatalinksLocked=T
|RECORD=46|OwnerIndex=1534
|RECORD=48|OwnerIndex=1534
|RECORD=41|OwnerIndex=1536|IndexInSheet=-1|OwnerPartId=-1|Color=8388608|FontID=1|IsHidden=T|Text=2D|Name=Available Preview Images
|RECORD=17|IndexInSheet=179|OwnerPartId=-1|ShowNetName=T|Location.X=1250|Location.Y=480|Orientation=1|Color=128|FontID=1|Text=+3.3V
|RECORD=17|IndexInSheet=180|OwnerPartId=-1|Style=4|ShowNetName=T|Location.X=1250|Location.Y=380|Orientation=3|Color=128|FontID=1|Text=GND
|RECORD=27|IndexInSheet=181|OwnerPartId=-1|LineWidth=1|Color=8388608|LocationCount=2|X1=1250|Y1=400|X2=1250|Y2=380
|RECORD=27|IndexInSheet=182|OwnerPartId=-1|LineWidth=1|Color=8388608|LocationCount=2|X1=1250|Y1=450|X2=1250|Y2=480
|RECORD=27|IndexInSheet=183|OwnerPartId=-1|LineWidth=1|Color=8388608|LocationCount=3|X1=1300|Y1=570|X2=1270|Y2=570|X3=1270|Y3=450
|RECORD=27|IndexInSheet=184|OwnerPartId=-1|LineWidth=1|Color=8388608|LocationCount=2|X1=1270|Y1=400|X2=1270|Y2=340
|RECORD=29|IndexInSheet=-1|OwnerPartId=-1|Location.X=430|Location.Y=260|Color=128
|RECORD=29|IndexInSheet=-1|OwnerPartId=-1|Location.X=430|Location.Y=610|Color=128
|RECORD=29|IndexInSheet=-1|OwnerPartId=-1|Location.X=680|Location.Y=220|Color=128
|RECORD=29|IndexInSheet=-1|OwnerPartId=-1|Location.X=680|Location.Y=310|Color=128
|RECORD=29|IndexInSheet=-1|OwnerPartId=-1|Location.X=680|Location.Y=570|Color=128
|RECORD=29|IndexInSheet=-1|OwnerPartId=-1|Location.X=740|Location.Y=130|Color=128
|RECORD=29|IndexInSheet=-1|OwnerPartId=-1|Location.X=740|Location.Y=480|Color=128
|RECORD=29|IndexInSheet=-1|OwnerPartId=-1|Location.X=750|Location.Y=130|Color=128
|RECORD=29|IndexInSheet=-1|OwnerPartId=-1|Location.X=750|Location.Y=270|Color=128
|RECORD=29|IndexInSheet=-1|OwnerPartId=-1|Location.X=750|Location.Y=480|Color=128
|RECORD=29|IndexInSheet=-1|OwnerPartId=-1|Location.X=750|Location.Y=620|Color=128
|RECORD=29|IndexInSheet=-1|OwnerPartId=-1|Location.X=760|Location.Y=130|Color=128
|RECORD=29|IndexInSheet=-1|OwnerPartId=-1|Location.X=760|Location.Y=480|Color=128
|RECORD=29|IndexInSheet=-1|OwnerPartId=-1|Location.X=1140|Location.Y=290|Color=128
|RECORD=29|IndexInSheet=-1|OwnerPartId=-1|Location.X=1140|Location.Y=610|Color=128
|RECORD=29|IndexInSheet=-1|OwnerPartId=-1|Location.X=1270|Location.Y=250|Color=128
|RECORD=29|IndexInSheet=-1|OwnerPartId=-1|Location.X=1270|Location.Y=340|Color=128
|RECORD=29|IndexInSheet=-1|OwnerPartId=-1|Location.X=1270|Location.Y=570|Color=128
|RECORD=29|IndexInSheet=-1|OwnerPartId=-1|Location.X=1330|Location.Y=160|Color=128
|RECORD=29|IndexInSheet=-1|OwnerPartId=-1|Location.X=1330|Location.Y=480|Color=128
|RECORD=29|IndexInSheet=-1|OwnerPartId=-1|Location.X=1340|Location.Y=160|Color=128
|RECORD=29|IndexInSheet=-1|OwnerPartId=-1|Location.X=1340|Location.Y=300|Color=128
|RECORD=29|IndexInSheet=-1|OwnerPartId=-1|Location.X=1340|Location.Y=480|Color=128
|RECORD=29|IndexInSheet=-1|OwnerPartId=-1|Location.X=1340|Location.Y=620|Color=128
|RECORD=29|IndexInSheet=-1|OwnerPartId=-1|Location.X=1350|Location.Y=160|Color=128
|RECORD=29|IndexInSheet=-1|OwnerPartId=-1|Location.X=1350|Location.Y=480|Color=128